FILE_TYPE = MACRO_DRAWING;
SET COLOR_WIRE YELLOW;
SET COLOR_PROP MONO;
SET COLOR_DOT WHITE;
SET COLOR_ARC YELLOW;
SET COLOR_BODY GREEN;
SET COLOR_NOTE MONO;
SET PROP_DISPLAY VALUE;
SET PAGE_NUMBER P240;
FORCEADD OFFPAGE..1
(5175 2725);
FORCEPROP 2 LAST $XR0 241 
J 0
(4923 2725);
DISPLAY 0.638298 (4923 2725);
PAINT MONO (4923 2725);
FORCEPROP 2 LAST PATH I107
J 0
(4925 2775);
DISPLAY 1.021277 (4925 2775);
PAINT ORANGE (4925 2775);
DISPLAY INVISIBLE (4925 2775);
FORCEPROP 2 LAST BOM_COST PVPP_KLM_VR
J 0
(4350 2800);
DISPLAY 1.042553 (4350 2800);
PAINT WHITE (4350 2800);
DISPLAY INVISIBLE (4350 2800);
FORCEPROP 2 LAST ROOM PVPP_KLM_VR
J 0
(4625 2800);
DISPLAY 1.042553 (4625 2800);
PAINT GREEN (4625 2800);
DISPLAY INVISIBLE (4625 2800);
FORCEPROP 0 LAST TOLERANCE 1%
J 0
(5225 2800);
PAINT SKYBLUE (5225 2800);
DISPLAY INVISIBLE (5225 2800);
FORCEPROP 2 LAST CDS_LIB mstr_standard
J 0
(5175 2725);
PAINT MONO (5175 2725);
DISPLAY INVISIBLE (5175 2725);
FORCEPROP 1 LAST OFFPAGE TRUE
J 0
(5500 2600);
PAINT GREEN (5500 2600);
DISPLAY INVISIBLE (5500 2600);
FORCEPROP 1 LAST COMMENT_BODY TRUE
J 0
(5300 2625);
DISPLAY 0.872340 (5300 2625);
PAINT PEACH (5300 2625);
DISPLAY INVISIBLE (5300 2625);
FORCEADD GND..1
(5625 2150);
FORCEPROP 3 LASTPIN (5625 2200) SIG_NAME GND\g
J 0
(5635 2210);
DISPLAY 0.659574 (5635 2210);
PAINT MONO (5635 2210);
DISPLAY INVISIBLE (5635 2210);
FORCEPROP 2 LAST ROOM PVPP_KLM_VR
J 0
(4875 2225);
DISPLAY 1.042553 (4875 2225);
PAINT GREEN (4875 2225);
DISPLAY INVISIBLE (4875 2225);
FORCEPROP 2 LAST BOM_COST PVPP_KLM_VR
J 0
(4875 2275);
DISPLAY 1.042553 (4875 2275);
PAINT WHITE (4875 2275);
DISPLAY INVISIBLE (4875 2275);
FORCEPROP 2 LAST BOM SYSB_CPLD
J 0
(4875 2325);
DISPLAY 1.042553 (4875 2325);
PAINT ORANGE (4875 2325);
DISPLAY INVISIBLE (4875 2325);
FORCEPROP 2 LAST CDS_LIB mstr_symbols
J 0
(5625 2150);
PAINT MONO (5625 2150);
DISPLAY INVISIBLE (5625 2150);
FORCEPROP 1 LAST VOLTAGE 0
J 0
(5625 2150);
PAINT SKYBLUE (5625 2150);
DISPLAY INVISIBLE (5625 2150);
FORCEPROP 1 LAST PATH I110
J 0
(5700 2150);
DISPLAY 0.872340 (5700 2150);
PAINT AQUA (5700 2150);
DISPLAY INVISIBLE (5700 2150);
FORCEPROP 1 LAST SIZE 1B
J 0
(5700 2100);
DISPLAY 0.680851 (5700 2100);
PAINT ORANGE (5700 2100);
DISPLAY INVISIBLE (5700 2100);
FORCEPROP 1 LAST BODY_TYPE PLUMBING
J 0
(5580 2107);
DISPLAY 0.340426 (5580 2107);
PAINT GREEN (5580 2107);
DISPLAY INVISIBLE (5580 2107);
FORCEPROP 1 LAST HDL_POWER GND
J 0
(5625 2300);
DISPLAY 0.680851 (5625 2300);
PAINT GREEN (5625 2300);
DISPLAY INVISIBLE (5625 2300);
FORCEADD RES..2
(5625 2400);
FORCEPROP 1 LAST WATTAGE 1/16W
J 0
(5665 2375);
DISPLAY 0.617021 (5665 2375);
PAINT SKYBLUE (5665 2375);
FORCEPROP 1 LAST MATERIAL EMPTY
J 0
(5665 2325);
DISPLAY 0.617021 (5665 2325);
PAINT RED (5665 2325);
FORCEPROP 1 LASTPIN (5625 2300) $PN 2
J 0
(5630 2310);
DISPLAY 0.617021 (5630 2310);
PAINT WHITE (5630 2310);
FORCEPROP 1 LASTPIN (5625 2500) $PN 1
J 0
(5630 2462);
DISPLAY 0.617021 (5630 2462);
PAINT WHITE (5630 2462);
FORCEPROP 1 LAST PACK_TYPE 0402
J 0
(5665 2225);
DISPLAY 0.617021 (5665 2225);
PAINT SKYBLUE (5665 2225);
FORCEPROP 1 LAST TOLERANCE 1%
J 0
(5670 2425);
DISPLAY 0.617021 (5670 2425);
PAINT SKYBLUE (5670 2425);
FORCEPROP 1 LAST VALUE 10.0K
J 0
(5670 2475);
DISPLAY 0.617021 (5670 2475);
PAINT SKYBLUE (5670 2475);
FORCEPROP 1 LAST LOCATION R8F1
J 0
(5670 2525);
DISPLAY 0.617021 (5670 2525);
PAINT AQUA (5670 2525);
FORCEPROP 1 LAST PART_NUMBER G21796-016
J 0
(5640 2275);
DISPLAY 0.617021 (5640 2275);
PAINT BLUE (5640 2275);
FORCEPROP 2 LAST CDS_LIB mstr_discrete
J 0
(5625 2400);
PAINT MONO (5625 2400);
DISPLAY INVISIBLE (5625 2400);
FORCEPROP 2 LAST CDS_LOCATION R8F1
J 0
(5670 2525);
DISPLAY 0.617021 (5670 2525);
PAINT AQUA (5670 2525);
DISPLAY INVISIBLE (5670 2525);
FORCEPROP 2 LAST ROOM P3V3_STBY_VR
J 0
(5675 2625);
DISPLAY 1.042553 (5675 2625);
PAINT GREEN (5675 2625);
DISPLAY INVISIBLE (5675 2625);
FORCEPROP 1 LAST PATH I111
J 0
(5675 2575);
DISPLAY 0.978723 (5675 2575);
PAINT WHITE (5675 2575);
DISPLAY INVISIBLE (5675 2575);
FORCEPROP 2 LAST $SEC 1
J 0
(5675 2625);
DISPLAY 0.680851 (5675 2625);
PAINT MONO (5675 2625);
DISPLAY INVISIBLE (5675 2625);
FORCEPROP 2 LAST CDS_SEC 1
J 0
(5675 2625);
DISPLAY 1.042553 (5675 2625);
PAINT ORANGE (5675 2625);
DISPLAY INVISIBLE (5675 2625);
FORCEPROP 0 LAST BOM SYSB_CPLD
J 0
(5675 2725);
DISPLAY 1.042553 (5675 2725);
PAINT ORANGE (5675 2725);
DISPLAY INVISIBLE (5675 2725);
FORCEPROP 2 LAST BOM_COST P3V3_STBY_VR
J 0
(5675 2625);
DISPLAY 1.042553 (5675 2625);
PAINT WHITE (5675 2625);
DISPLAY INVISIBLE (5675 2625);
FORCEADD CAP..1
R 2
(6175 2475);
FORCEPROP 1 LAST VALUE 1000PF
J 2
(6125 2525);
DISPLAY 0.617021 (6125 2525);
PAINT SKYBLUE (6125 2525);
FORCEPROP 1 LAST TOLERANCE 10%
J 2
(6125 2425);
DISPLAY 0.617021 (6125 2425);
PAINT SKYBLUE (6125 2425);
FORCEPROP 1 LAST PACK_TYPE 0402LF
J 2
(6125 2275);
DISPLAY 0.617021 (6125 2275);
PAINT SKYBLUE (6125 2275);
FORCEPROP 1 LAST MATERIAL EMPTY
J 2
(6125 2375);
DISPLAY 0.617021 (6125 2375);
PAINT RED (6125 2375);
FORCEPROP 1 LAST VOLTAGE 50V
J 2
(6125 2475);
DISPLAY 0.617021 (6125 2475);
PAINT SKYBLUE (6125 2475);
FORCEPROP 1 LAST LOCATION C8E17
J 2
(6125 2575);
DISPLAY 0.617021 (6125 2575);
PAINT AQUA (6125 2575);
FORCEPROP 1 LASTPIN (6175 2575) $PN 1
J 2
(6165 2555);
DISPLAY 0.617021 (6165 2555);
PAINT WHITE (6165 2555);
FORCEPROP 1 LASTPIN (6175 2375) $PN 2
J 2
(6165 2355);
DISPLAY 0.617021 (6165 2355);
PAINT WHITE (6165 2355);
FORCEPROP 1 LAST PART_NUMBER A36096-046
J 2
(6150 2325);
DISPLAY 0.617021 (6150 2325);
PAINT BLUE (6150 2325);
FORCEPROP 1 LAST PATH I113
J 2
(6125 2625);
DISPLAY 0.978723 (6125 2625);
PAINT WHITE (6125 2625);
DISPLAY INVISIBLE (6125 2625);
FORCEPROP 2 LAST CDS_LOCATION C8E17
J 2
(6125 2575);
DISPLAY 0.617021 (6125 2575);
PAINT AQUA (6125 2575);
DISPLAY INVISIBLE (6125 2575);
FORCEPROP 2 LAST $SEC 1
J 2
(6125 2675);
DISPLAY 0.680851 (6125 2675);
PAINT MONO (6125 2675);
DISPLAY INVISIBLE (6125 2675);
FORCEPROP 2 LAST CDS_SEC 1
J 2
(6125 2675);
DISPLAY 1.042553 (6125 2675);
PAINT ORANGE (6125 2675);
DISPLAY INVISIBLE (6125 2675);
FORCEPROP 0 LAST REUSE_ID 1
J 2
(6125 2675);
DISPLAY 1.042553 (6125 2675);
PAINT ORANGE (6125 2675);
DISPLAY INVISIBLE (6125 2675);
FORCEPROP 0 LAST FIN VR_1P2
J 2
(6125 2775);
PAINT ORANGE (6125 2775);
DISPLAY INVISIBLE (6125 2775);
FORCEPROP 2 LAST ROOM P3V3_STBY_VR
J 2
(6175 2475);
PAINT GREEN (6175 2475);
DISPLAY INVISIBLE (6175 2475);
FORCEPROP 2 LAST CDS_LIB mstr_discrete
J 2
(6175 2475);
PAINT MONO (6175 2475);
DISPLAY INVISIBLE (6175 2475);
FORCEPROP 2 LAST BOM_COST P3V3_STBY_VR
J 2
(6175 2475);
PAINT WHITE (6175 2475);
DISPLAY INVISIBLE (6175 2475);
FORCEADD P5V_STBY..1
(5725 3600);
FORCEPROP 3 LASTPIN (5725 3550) SIG_NAME P5V_STBY\g
J 0
(5735 3560);
DISPLAY 0.659574 (5735 3560);
PAINT MONO (5735 3560);
DISPLAY INVISIBLE (5735 3560);
FORCEPROP 1 LAST VOLTAGE +5.0V
J 0
(5925 3750);
DISPLAY 1.021277 (5925 3750);
PAINT SKYBLUE (5925 3750);
DISPLAY INVISIBLE (5925 3750);
FORCEPROP 2 LAST CDS_LIB mstr_symbols
J 0
(5725 3600);
PAINT MONO (5725 3600);
DISPLAY INVISIBLE (5725 3600);
FORCEPROP 1 LAST SIZE 1B
J 0
(5770 3622);
DISPLAY 0.340426 (5770 3622);
PAINT GREEN (5770 3622);
DISPLAY INVISIBLE (5770 3622);
FORCEPROP 1 LAST PATH I114
J 0
(5770 3602);
DISPLAY 0.340426 (5770 3602);
PAINT GREEN (5770 3602);
DISPLAY INVISIBLE (5770 3602);
FORCEPROP 1 LAST BODY_TYPE PLUMBING
J 0
(5680 3557);
DISPLAY 0.340426 (5680 3557);
PAINT GREEN (5680 3557);
DISPLAY INVISIBLE (5680 3557);
FORCEPROP 1 LAST HDL_POWER P5V_STBY
J 0
(5425 3475);
DISPLAY 0.872340 (5425 3475);
PAINT ORANGE (5425 3475);
DISPLAY INVISIBLE (5425 3475);
FORCEADD GND..1
(6350 3100);
FORCEPROP 3 LASTPIN (6350 3150) SIG_NAME GND\g
J 0
(6360 3160);
DISPLAY 0.659574 (6360 3160);
PAINT MONO (6360 3160);
DISPLAY INVISIBLE (6360 3160);
FORCEPROP 2 LAST BOM_COST PVPP_KLM_VR
J 0
(5450 3250);
DISPLAY 1.042553 (5450 3250);
PAINT WHITE (5450 3250);
DISPLAY INVISIBLE (5450 3250);
FORCEPROP 2 LAST ROOM PVPP_KLM_VR
J 0
(5700 3250);
PAINT GREEN (5700 3250);
DISPLAY INVISIBLE (5700 3250);
FORCEPROP 2 LAST CDS_LIB mstr_symbols
J 0
(6350 3175);
PAINT MONO (6350 3175);
DISPLAY INVISIBLE (6350 3175);
FORCEPROP 1 LAST VOLTAGE 0
J 0
(6350 3175);
PAINT SKYBLUE (6350 3175);
DISPLAY INVISIBLE (6350 3175);
FORCEPROP 1 LAST PATH I115
J 0
(6425 3100);
DISPLAY 0.872340 (6425 3100);
PAINT AQUA (6425 3100);
DISPLAY INVISIBLE (6425 3100);
FORCEPROP 1 LAST SIZE 1B
J 0
(6425 3125);
DISPLAY 0.893617 (6425 3125);
PAINT GREEN (6425 3125);
DISPLAY INVISIBLE (6425 3125);
FORCEPROP 1 LAST BODY_TYPE PLUMBING
J 0
(6305 3057);
DISPLAY 0.340426 (6305 3057);
PAINT GREEN (6305 3057);
DISPLAY INVISIBLE (6305 3057);
FORCEPROP 1 LAST HDL_POWER GND
J 0
(6350 3325);
DISPLAY 0.893617 (6350 3325);
PAINT GREEN (6350 3325);
DISPLAY INVISIBLE (6350 3325);
FORCEADD CAP..1
(6350 3350);
FORCEPROP 1 LAST VOLTAGE 50V
J 0
(6400 3350);
DISPLAY 0.617021 (6400 3350);
PAINT SKYBLUE (6400 3350);
FORCEPROP 1 LAST TOLERANCE 10%
J 0
(6400 3300);
DISPLAY 0.617021 (6400 3300);
PAINT SKYBLUE (6400 3300);
FORCEPROP 1 LAST PACK_TYPE 0402LF
J 0
(6400 3200);
DISPLAY 0.617021 (6400 3200);
PAINT SKYBLUE (6400 3200);
FORCEPROP 1 LASTPIN (6350 3250) $PN 2
J 0
(6360 3230);
DISPLAY 0.617021 (6360 3230);
PAINT WHITE (6360 3230);
FORCEPROP 1 LASTPIN (6350 3450) $PN 1
J 0
(6360 3430);
DISPLAY 0.617021 (6360 3430);
PAINT WHITE (6360 3430);
FORCEPROP 1 LAST PART_NUMBER A36096-046
J 0
(6400 3150);
DISPLAY 0.617021 (6400 3150);
PAINT BLUE (6400 3150);
FORCEPROP 1 LAST LOCATION C8F2
J 0
(6400 3450);
DISPLAY 0.617021 (6400 3450);
PAINT AQUA (6400 3450);
FORCEPROP 1 LAST VALUE 1000PF
J 0
(6400 3400);
DISPLAY 0.617021 (6400 3400);
PAINT SKYBLUE (6400 3400);
FORCEPROP 1 LAST MATERIAL X7R
J 0
(6400 3250);
DISPLAY 0.617021 (6400 3250);
PAINT SKYBLUE (6400 3250);
FORCEPROP 2 LAST BOM_COST P3V3_STBY_VR
J 0
(6350 3350);
PAINT WHITE (6350 3350);
DISPLAY INVISIBLE (6350 3350);
FORCEPROP 2 LAST CDS_LIB mstr_discrete
J 2
(6350 3350);
PAINT MONO (6350 3350);
DISPLAY INVISIBLE (6350 3350);
FORCEPROP 2 LAST ROOM P3V3_STBY_VR
J 0
(6350 3350);
PAINT GREEN (6350 3350);
DISPLAY INVISIBLE (6350 3350);
FORCEPROP 2 LAST $SEC 1
J 2
(6400 3550);
DISPLAY 0.680851 (6400 3550);
PAINT MONO (6400 3550);
DISPLAY INVISIBLE (6400 3550);
FORCEPROP 2 LAST CDS_LOCATION C8F2
J 0
(6400 3450);
DISPLAY 0.617021 (6400 3450);
PAINT AQUA (6400 3450);
DISPLAY INVISIBLE (6400 3450);
FORCEPROP 1 LAST PATH I116
J 0
(6400 3500);
DISPLAY 0.978723 (6400 3500);
PAINT WHITE (6400 3500);
DISPLAY INVISIBLE (6400 3500);
FORCEPROP 2 LAST CDS_SEC 1
J 2
(6400 3550);
DISPLAY 1.042553 (6400 3550);
PAINT ORANGE (6400 3550);
DISPLAY INVISIBLE (6400 3550);
FORCEPROP 2 LAST REUSE_ID 17
J 0
(6400 3550);
DISPLAY 1.042553 (6400 3550);
PAINT ORANGE (6400 3550);
DISPLAY INVISIBLE (6400 3550);
FORCEADD RES..2
R 2
(6275 3900);
FORCEPROP 1 LASTPIN (6275 3800) $PN 2
J 2
(6270 3810);
DISPLAY 0.617021 (6270 3810);
PAINT WHITE (6270 3810);
FORCEPROP 1 LASTPIN (6275 4000) $PN 1
J 2
(6270 3962);
DISPLAY 0.617021 (6270 3962);
PAINT WHITE (6270 3962);
FORCEPROP 1 LAST LOCATION R8F5
J 2
(6230 4025);
DISPLAY 0.617021 (6230 4025);
PAINT AQUA (6230 4025);
FORCEPROP 1 LAST VALUE 1.00K
J 2
(6230 3975);
DISPLAY 0.617021 (6230 3975);
PAINT SKYBLUE (6230 3975);
FORCEPROP 1 LAST TOLERANCE 1%
J 2
(6230 3925);
DISPLAY 0.617021 (6230 3925);
PAINT SKYBLUE (6230 3925);
FORCEPROP 1 LAST WATTAGE 1/16W
J 2
(6235 3875);
DISPLAY 0.617021 (6235 3875);
PAINT SKYBLUE (6235 3875);
FORCEPROP 1 LAST MATERIAL CHIP
J 2
(6235 3825);
DISPLAY 0.617021 (6235 3825);
PAINT SKYBLUE (6235 3825);
FORCEPROP 1 LAST PART_NUMBER G21796-026
J 2
(6235 3775);
DISPLAY 0.617021 (6235 3775);
PAINT BLUE (6235 3775);
FORCEPROP 1 LAST PACK_TYPE 0402
J 2
(6235 3725);
DISPLAY 0.617021 (6235 3725);
PAINT SKYBLUE (6235 3725);
FORCEPROP 2 LAST CDS_LOCATION R8F5
J 2
(6230 4025);
DISPLAY 0.617021 (6230 4025);
PAINT AQUA (6230 4025);
DISPLAY INVISIBLE (6230 4025);
FORCEPROP 2 LAST CDS_LIB mstr_discrete
J 2
(6275 3900);
PAINT MONO (6275 3900);
DISPLAY INVISIBLE (6275 3900);
FORCEPROP 2 LAST ROOM PVPP_KLM_VR
J 2
(6215 4065);
PAINT GREEN (6215 4065);
DISPLAY INVISIBLE (6215 4065);
FORCEPROP 1 LAST PATH I117
J 2
(6225 4075);
DISPLAY 0.978723 (6225 4075);
PAINT WHITE (6225 4075);
DISPLAY INVISIBLE (6225 4075);
FORCEPROP 2 LAST BOM_COST P3V3_STBY_VR
J 2
(6215 4090);
DISPLAY 1.042553 (6215 4090);
PAINT WHITE (6215 4090);
DISPLAY INVISIBLE (6215 4090);
FORCEPROP 2 LAST SEC 1
J 2
(6225 4125);
DISPLAY 0.680851 (6225 4125);
PAINT MONO (6225 4125);
DISPLAY INVISIBLE (6225 4125);
FORCEPROP 2 LAST REUSE_ID 21
J 2
(6225 4125);
DISPLAY 1.042553 (6225 4125);
PAINT ORANGE (6225 4125);
DISPLAY INVISIBLE (6225 4125);
FORCEPROP 2 LAST SEC_TYPE 0402
J 2
(6225 4125);
DISPLAY 1.042553 (6225 4125);
PAINT ORANGE (6225 4125);
DISPLAY INVISIBLE (6225 4125);
FORCEADD RT8240..1
(7550 2625);
FORCEPROP 2 LASTPIN (7150 2375) $PN 12
J 2
(7140 2385);
DISPLAY 0.617021 (7140 2385);
PAINT ORANGE (7140 2385);
FORCEPROP 2 LASTPIN (7150 2425) $PN 13
J 2
(7140 2435);
DISPLAY 0.617021 (7140 2435);
PAINT ORANGE (7140 2435);
FORCEPROP 2 LASTPIN (7150 2675) $PN 11
J 2
(7140 2685);
DISPLAY 0.617021 (7140 2685);
PAINT ORANGE (7140 2685);
FORCEPROP 2 LASTPIN (7150 2825) $PN 9
J 2
(7140 2835);
DISPLAY 0.617021 (7140 2835);
PAINT ORANGE (7140 2835);
FORCEPROP 2 LASTPIN (7150 2875) $PN 5
J 2
(7140 2885);
DISPLAY 0.617021 (7140 2885);
PAINT ORANGE (7140 2885);
FORCEPROP 2 LASTPIN (7950 2375) $PN 7
J 0
(7960 2385);
DISPLAY 0.617021 (7960 2385);
PAINT ORANGE (7960 2385);
FORCEPROP 2 LASTPIN (7950 2475) $PN 6
J 0
(7960 2485);
DISPLAY 0.617021 (7960 2485);
PAINT ORANGE (7960 2485);
FORCEPROP 2 LASTPIN (7950 2775) $PN 3
J 0
(7960 2785);
DISPLAY 0.617021 (7960 2785);
PAINT ORANGE (7960 2785);
FORCEPROP 2 LASTPIN (7950 2675) $PN 2
J 0
(7960 2685);
DISPLAY 0.617021 (7960 2685);
PAINT ORANGE (7960 2685);
FORCEPROP 2 LASTPIN (7950 2575) $PN 1
J 0
(7960 2585);
DISPLAY 0.617021 (7960 2585);
PAINT ORANGE (7960 2585);
FORCEPROP 2 LASTPIN (7950 2875) $PN 4
J 0
(7960 2885);
DISPLAY 0.617021 (7960 2885);
PAINT ORANGE (7960 2885);
FORCEPROP 1 LAST LOCATION EU8F1
J 0
(7200 3125);
DISPLAY 0.617021 (7200 3125);
PAINT AQUA (7200 3125);
FORCEPROP 1 LAST MATERIAL IC
J 0
(7200 3075);
DISPLAY 0.617021 (7200 3075);
PAINT SKYBLUE (7200 3075);
FORCEPROP 2 LASTPIN (7150 2725) $PN 8
J 2
(7140 2735);
DISPLAY 0.617021 (7140 2735);
PAINT ORANGE (7140 2735);
FORCEPROP 2 LASTPIN (7150 2325) $PN 10
J 2
(7140 2335);
DISPLAY 0.617021 (7140 2335);
PAINT ORANGE (7140 2335);
FORCEPROP 1 LAST PART_NUMBER H66262-001
J 0
(7200 2175);
DISPLAY 0.617021 (7200 2175);
PAINT BLUE (7200 2175);
FORCEPROP 2 LAST CDS_LIB mstr_vreg
J 0
(7550 2625);
PAINT MONO (7550 2625);
DISPLAY INVISIBLE (7550 2625);
FORCEPROP 0 LAST ROOM P3V3_STBY_VR
J 0
(7200 3225);
DISPLAY 1.021277 (7200 3225);
PAINT ORANGE (7200 3225);
DISPLAY INVISIBLE (7200 3225);
FORCEPROP 2 LAST CDS_LOCATION EU8F1
J 0
(7200 3125);
DISPLAY 0.617021 (7200 3125);
PAINT AQUA (7200 3125);
DISPLAY INVISIBLE (7200 3125);
FORCEPROP 2 LAST SEC 1
J 0
(7200 3175);
DISPLAY 0.680851 (7200 3175);
PAINT MONO (7200 3175);
DISPLAY INVISIBLE (7200 3175);
FORCEPROP 2 LAST SEC_TYPE QFN
J 0
(7200 3175);
DISPLAY 1.021277 (7200 3175);
PAINT ORANGE (7200 3175);
DISPLAY INVISIBLE (7200 3175);
FORCEPROP 1 LAST PACK_TYPE QFN
J 0
(7200 3175);
PAINT SKYBLUE (7200 3175);
DISPLAY INVISIBLE (7200 3175);
FORCEPROP 1 LAST PATH I125
J 0
(7600 3075);
PAINT GREEN (7600 3075);
DISPLAY INVISIBLE (7600 3075);
FORCEADD OFFPAGE..2
(7825 3825);
FORCEPROP 2 LAST $XR5 239 
J 0
(8254 3789);
DISPLAY 0.638298 (8254 3789);
PAINT MONO (8254 3789);
FORCEPROP 2 LAST $XR4 237 
J 0
(8134 3789);
DISPLAY 0.638298 (8134 3789);
PAINT MONO (8134 3789);
FORCEPROP 2 LAST $XR3 196 
J 0
(8014 3789);
DISPLAY 0.638298 (8014 3789);
PAINT MONO (8014 3789);
FORCEPROP 2 LAST $XR2 191 
J 0
(8254 3825);
DISPLAY 0.638298 (8254 3825);
PAINT MONO (8254 3825);
FORCEPROP 2 LAST $XR1 189 
J 0
(8134 3825);
DISPLAY 0.638298 (8134 3825);
PAINT MONO (8134 3825);
FORCEPROP 2 LAST $XR0 101 
J 0
(8014 3825);
DISPLAY 0.638298 (8014 3825);
PAINT MONO (8014 3825);
FORCEPROP 2 LAST BOM_COST PVPP_KLM_VR
J 0
(7125 3900);
DISPLAY 1.042553 (7125 3900);
PAINT WHITE (7125 3900);
DISPLAY INVISIBLE (7125 3900);
FORCEPROP 2 LAST ROOM PVPP_KLM_VR
J 0
(7400 3900);
DISPLAY 1.042553 (7400 3900);
PAINT GREEN (7400 3900);
DISPLAY INVISIBLE (7400 3900);
FORCEPROP 2 LAST CDS_LIB mstr_standard
J 2
(7825 3825);
PAINT MONO (7825 3825);
DISPLAY INVISIBLE (7825 3825);
FORCEPROP 0 LAST TOLERANCE 1%
J 0
(8000 3900);
PAINT SKYBLUE (8000 3900);
DISPLAY INVISIBLE (8000 3900);
FORCEPROP 2 LAST PATH I126
J 0
(8025 3875);
DISPLAY 1.021277 (8025 3875);
PAINT ORANGE (8025 3875);
DISPLAY INVISIBLE (8025 3875);
FORCEPROP 1 LAST OFFPAGE TRUE
J 0
(8150 3700);
PAINT GREEN (8150 3700);
DISPLAY INVISIBLE (8150 3700);
FORCEPROP 1 LAST COMMENT_BODY TRUE
J 0
(7780 3730);
DISPLAY 0.872340 (7780 3730);
PAINT PEACH (7780 3730);
DISPLAY INVISIBLE (7780 3730);
FORCEADD RES..1
(7600 3425);
FORCEPROP 1 LAST VALUE 0.0
J 2
(7500 3300);
DISPLAY 0.617021 (7500 3300);
PAINT SKYBLUE (7500 3300);
FORCEPROP 1 LAST WATTAGE 1/16W
J 2
(7575 3250);
DISPLAY 0.617021 (7575 3250);
PAINT SKYBLUE (7575 3250);
FORCEPROP 1 LAST TOLERANCE 5%
J 0
(7550 3300);
DISPLAY 0.617021 (7550 3300);
PAINT SKYBLUE (7550 3300);
FORCEPROP 1 LASTPIN (7500 3425) $PN 1
J 0
(7512 3437);
DISPLAY 0.617021 (7512 3437);
PAINT WHITE (7512 3437);
FORCEPROP 1 LASTPIN (7700 3425) $PN 2
J 0
(7662 3437);
DISPLAY 0.617021 (7662 3437);
PAINT WHITE (7662 3437);
FORCEPROP 1 LAST LOCATION R8E35
J 0
(7550 3475);
DISPLAY 0.617021 (7550 3475);
PAINT AQUA (7550 3475);
FORCEPROP 1 LAST PACK_TYPE 0402
J 0
(7650 3300);
DISPLAY 0.617021 (7650 3300);
PAINT SKYBLUE (7650 3300);
FORCEPROP 1 LAST PART_NUMBER G21497-005
J 0
(7450 3350);
DISPLAY 0.617021 (7450 3350);
PAINT BLUE (7450 3350);
FORCEPROP 1 LAST MATERIAL CHIP
J 0
(7600 3250);
DISPLAY 0.617021 (7600 3250);
PAINT SKYBLUE (7600 3250);
FORCEPROP 2 LAST CDS_LOCATION R8E35
J 0
(7550 3475);
DISPLAY 0.617021 (7550 3475);
PAINT AQUA (7550 3475);
DISPLAY INVISIBLE (7550 3475);
FORCEPROP 2 LAST ROOM P3V3_STBY_VR
J 0
(7600 3425);
PAINT GREEN (7600 3425);
DISPLAY INVISIBLE (7600 3425);
FORCEPROP 2 LAST CDS_LIB mstr_discrete
J 0
(7600 3425);
PAINT MONO (7600 3425);
DISPLAY INVISIBLE (7600 3425);
FORCEPROP 2 LAST BOM_COST P3V3_STBY_VR
J 0
(7600 3425);
PAINT WHITE (7600 3425);
DISPLAY INVISIBLE (7600 3425);
FORCEPROP 1 LAST PATH I127
J 0
(7550 3575);
DISPLAY 0.978723 (7550 3575);
PAINT WHITE (7550 3575);
DISPLAY INVISIBLE (7550 3575);
FORCEPROP 0 LAST SPOF TRUE
J 0
(7550 3575);
DISPLAY 1.021277 (7550 3575);
PAINT ORANGE (7550 3575);
DISPLAY INVISIBLE (7550 3575);
FORCEPROP 2 LAST REUSE_ID 13
J 0
(7550 3625);
DISPLAY 1.042553 (7550 3625);
PAINT ORANGE (7550 3625);
DISPLAY INVISIBLE (7550 3625);
FORCEPROP 2 LAST CDS_SEC 1
J 0
(7550 3625);
DISPLAY 1.042553 (7550 3625);
PAINT ORANGE (7550 3625);
DISPLAY INVISIBLE (7550 3625);
FORCEPROP 2 LAST $SEC 1
J 0
(7550 3625);
DISPLAY 0.680851 (7550 3625);
PAINT MONO (7550 3625);
DISPLAY INVISIBLE (7550 3625);
FORCEADD GND..1
(8475 4150);
FORCEPROP 3 LASTPIN (8475 4200) SIG_NAME GND\g
J 0
(8485 4210);
DISPLAY 0.659574 (8485 4210);
PAINT MONO (8485 4210);
DISPLAY INVISIBLE (8485 4210);
FORCEPROP 1 LAST VOLTAGE 0
J 0
(8475 4150);
PAINT SKYBLUE (8475 4150);
DISPLAY INVISIBLE (8475 4150);
FORCEPROP 2 LAST CDS_LIB mstr_symbols
J 0
(8475 4150);
PAINT MONO (8475 4150);
DISPLAY INVISIBLE (8475 4150);
FORCEPROP 2 LAST BOM_COST PVPP_KLM_VR
J 0
(7625 4225);
DISPLAY 1.042553 (7625 4225);
PAINT WHITE (7625 4225);
DISPLAY INVISIBLE (7625 4225);
FORCEPROP 2 LAST ROOM PVPP_KLM_VR
J 0
(7900 4225);
DISPLAY 1.042553 (7900 4225);
PAINT GREEN (7900 4225);
DISPLAY INVISIBLE (7900 4225);
FORCEPROP 1 LAST PATH I128
J 0
(8550 4150);
DISPLAY 0.872340 (8550 4150);
PAINT AQUA (8550 4150);
DISPLAY INVISIBLE (8550 4150);
FORCEPROP 1 LAST SIZE 1B
J 0
(8550 4100);
DISPLAY 0.872340 (8550 4100);
PAINT GREEN (8550 4100);
DISPLAY INVISIBLE (8550 4100);
FORCEPROP 1 LAST BODY_TYPE PLUMBING
J 0
(8430 4107);
DISPLAY 0.340426 (8430 4107);
PAINT GREEN (8430 4107);
DISPLAY INVISIBLE (8430 4107);
FORCEPROP 1 LAST HDL_POWER GND
J 0
(8475 4300);
DISPLAY 0.872340 (8475 4300);
PAINT GREEN (8475 4300);
DISPLAY INVISIBLE (8475 4300);
FORCEADD CAP..2
R 2
(8300 3425);
FORCEPROP 1 LASTPIN (8200 3425) $PN 2
J 2
(8215 3440);
DISPLAY 0.617021 (8215 3440);
PAINT WHITE (8215 3440);
FORCEPROP 1 LAST MATERIAL X7R
J 2
(8300 3275);
DISPLAY 0.617021 (8300 3275);
PAINT SKYBLUE (8300 3275);
FORCEPROP 1 LAST PACK_TYPE 0603LF
J 1
(8300 3225);
DISPLAY 0.617021 (8300 3225);
PAINT SKYBLUE (8300 3225);
FORCEPROP 1 LAST VOLTAGE 25V
J 2
(8300 3325);
DISPLAY 0.617021 (8300 3325);
PAINT SKYBLUE (8300 3325);
FORCEPROP 1 LAST VALUE 0.1UF
J 0
(8300 3325);
DISPLAY 0.617021 (8300 3325);
PAINT SKYBLUE (8300 3325);
FORCEPROP 1 LAST LOCATION C8E12
J 1
(8300 3525);
DISPLAY 0.617021 (8300 3525);
PAINT AQUA (8300 3525);
FORCEPROP 1 LAST TOLERANCE 10%
J 0
(8300 3275);
DISPLAY 0.617021 (8300 3275);
PAINT SKYBLUE (8300 3275);
FORCEPROP 1 LAST PART_NUMBER 602433-020
J 1
(8300 3475);
DISPLAY 0.617021 (8300 3475);
PAINT BLUE (8300 3475);
FORCEPROP 1 LASTPIN (8400 3425) $PN 1
J 2
(8410 3440);
DISPLAY 0.617021 (8410 3440);
PAINT WHITE (8410 3440);
FORCEPROP 2 LAST ROOM P3V3_STBY_VR
J 2
(8300 3550);
DISPLAY 0.765957 (8300 3550);
PAINT GREEN (8300 3550);
DISPLAY INVISIBLE (8300 3550);
FORCEPROP 2 LAST CDS_LOCATION C8E12
J 1
(8300 3525);
DISPLAY 0.617021 (8300 3525);
PAINT AQUA (8300 3525);
DISPLAY INVISIBLE (8300 3525);
FORCEPROP 2 LAST CDS_LIB mstr_discrete
J 0
(8300 3425);
PAINT MONO (8300 3425);
DISPLAY INVISIBLE (8300 3425);
FORCEPROP 2 LAST BOM_COST P3V3_STBY_VR
J 0
(8255 3585);
DISPLAY 1.042553 (8255 3585);
PAINT WHITE (8255 3585);
DISPLAY INVISIBLE (8255 3585);
FORCEPROP 2 LAST REUSE_ID 27
J 0
(8300 3675);
DISPLAY 1.042553 (8300 3675);
PAINT ORANGE (8300 3675);
DISPLAY INVISIBLE (8300 3675);
FORCEPROP 0 LAST SPOF TRUE
J 0
(8300 3625);
DISPLAY 1.021277 (8300 3625);
PAINT ORANGE (8300 3625);
DISPLAY INVISIBLE (8300 3625);
FORCEPROP 2 LAST CDS_SEC 1
J 0
(8255 3635);
DISPLAY 1.042553 (8255 3635);
PAINT ORANGE (8255 3635);
DISPLAY INVISIBLE (8255 3635);
FORCEPROP 2 LAST $SEC 1
J 0
(8300 3675);
DISPLAY 0.680851 (8300 3675);
PAINT MONO (8300 3675);
DISPLAY INVISIBLE (8300 3675);
FORCEPROP 1 LAST PATH I129
J 2
(8300 3625);
DISPLAY 0.978723 (8300 3625);
PAINT WHITE (8300 3625);
DISPLAY INVISIBLE (8300 3625);
FORCEADD P3V3_STBY..1
(6275 4150);
FORCEPROP 3 LASTPIN (6275 4100) SIG_NAME P3V3_STBY\g
J 0
(6285 4110);
DISPLAY 0.659574 (6285 4110);
PAINT MONO (6285 4110);
DISPLAY INVISIBLE (6285 4110);
FORCEPROP 1 LAST PATH I130
J 0
(6320 4152);
DISPLAY 0.340426 (6320 4152);
PAINT GREEN (6320 4152);
DISPLAY INVISIBLE (6320 4152);
FORCEPROP 2 LAST CDS_LIB mstr_symbols
J 0
(6275 4150);
PAINT MONO (6275 4150);
DISPLAY INVISIBLE (6275 4150);
FORCEPROP 1 LAST SIZE 1B
J 0
(6320 4172);
DISPLAY 0.340426 (6320 4172);
PAINT GREEN (6320 4172);
DISPLAY INVISIBLE (6320 4172);
FORCEPROP 1 LAST VOLTAGE +3.3V
J 0
(6475 4300);
DISPLAY 1.021277 (6475 4300);
PAINT SKYBLUE (6475 4300);
DISPLAY INVISIBLE (6475 4300);
FORCEPROP 1 LAST BODY_TYPE PLUMBING
J 0
(6230 4107);
DISPLAY 0.340426 (6230 4107);
PAINT GREEN (6230 4107);
DISPLAY INVISIBLE (6230 4107);
FORCEPROP 1 LAST HDL_POWER P3V3_STBY
J 0
(5975 4025);
DISPLAY 0.872340 (5975 4025);
PAINT ORANGE (5975 4025);
DISPLAY INVISIBLE (5975 4025);
FORCEADD P12V_STBY..1
(5700 4750);
FORCEPROP 3 LASTPIN (5700 4700) SIG_NAME P12V_STBY\g
J 0
(5710 4710);
DISPLAY 0.659574 (5710 4710);
PAINT MONO (5710 4710);
DISPLAY INVISIBLE (5710 4710);
FORCEPROP 1 LAST SIZE 1B
J 0
(5745 4772);
DISPLAY 0.340426 (5745 4772);
PAINT GREEN (5745 4772);
DISPLAY INVISIBLE (5745 4772);
FORCEPROP 2 LAST CDS_LIB mstr_symbols
J 0
(5700 4750);
PAINT ORANGE (5700 4750);
DISPLAY INVISIBLE (5700 4750);
FORCEPROP 1 LAST PATH I131
J 0
(5745 4752);
DISPLAY 0.340426 (5745 4752);
PAINT GREEN (5745 4752);
DISPLAY INVISIBLE (5745 4752);
FORCEPROP 1 LAST VOLTAGE 12.0V
J 0
(5655 4707);
DISPLAY 0.340426 (5655 4707);
PAINT SKYBLUE (5655 4707);
DISPLAY INVISIBLE (5655 4707);
FORCEPROP 1 LAST BODY_TYPE PLUMBING
J 0
(5655 4707);
DISPLAY 0.340426 (5655 4707);
PAINT GREEN (5655 4707);
DISPLAY INVISIBLE (5655 4707);
FORCEPROP 1 LAST HDL_POWER P12V_STBY
J 0
(5400 4625);
DISPLAY 0.872340 (5400 4625);
PAINT ORANGE (5400 4625);
DISPLAY INVISIBLE (5400 4625);
FORCEADD CAP..1
(8150 4325);
FORCEPROP 1 LAST PART_NUMBER D38464-005
J 0
(8200 4175);
DISPLAY 0.617021 (8200 4175);
PAINT BLUE (8200 4175);
FORCEPROP 1 LAST PACK_TYPE 1206LF
J 0
(8200 4125);
DISPLAY 0.617021 (8200 4125);
PAINT SKYBLUE (8200 4125);
FORCEPROP 1 LAST TOLERANCE 10%
J 0
(8200 4275);
DISPLAY 0.617021 (8200 4275);
PAINT SKYBLUE (8200 4275);
FORCEPROP 1 LAST VOLTAGE 16V
J 0
(8200 4325);
DISPLAY 0.617021 (8200 4325);
PAINT SKYBLUE (8200 4325);
FORCEPROP 1 LAST VALUE 22UF
J 0
(8200 4375);
DISPLAY 0.617021 (8200 4375);
PAINT SKYBLUE (8200 4375);
FORCEPROP 1 LAST LOCATION C8E10
J 0
(8200 4425);
DISPLAY 0.617021 (8200 4425);
PAINT AQUA (8200 4425);
FORCEPROP 1 LAST MATERIAL X6S
J 0
(8200 4225);
DISPLAY 0.617021 (8200 4225);
PAINT SKYBLUE (8200 4225);
FORCEPROP 1 LASTPIN (8150 4225) $PN 2
J 0
(8160 4205);
DISPLAY 0.617021 (8160 4205);
PAINT WHITE (8160 4205);
FORCEPROP 1 LASTPIN (8150 4425) $PN 1
J 0
(8160 4405);
DISPLAY 0.617021 (8160 4405);
PAINT WHITE (8160 4405);
FORCEPROP 2 LAST CDS_SEC 1
J 0
(8200 4525);
DISPLAY 1.042553 (8200 4525);
PAINT ORANGE (8200 4525);
DISPLAY INVISIBLE (8200 4525);
FORCEPROP 2 LAST $SEC 1
J 0
(8200 4525);
DISPLAY 0.680851 (8200 4525);
PAINT MONO (8200 4525);
DISPLAY INVISIBLE (8200 4525);
FORCEPROP 2 LAST CDS_LOCATION C8E10
J 0
(8200 4425);
DISPLAY 0.617021 (8200 4425);
PAINT AQUA (8200 4425);
DISPLAY INVISIBLE (8200 4425);
FORCEPROP 1 LAST PATH I137
J 0
(8200 4475);
DISPLAY 0.978723 (8200 4475);
PAINT WHITE (8200 4475);
DISPLAY INVISIBLE (8200 4475);
FORCEPROP 2 LAST BOM_COST P3V3_STBY_VR
J 0
(8150 4325);
PAINT WHITE (8150 4325);
DISPLAY INVISIBLE (8150 4325);
FORCEPROP 2 LAST CDS_LIB mstr_discrete
J 0
(8150 4325);
PAINT MONO (8150 4325);
DISPLAY INVISIBLE (8150 4325);
FORCEPROP 2 LAST ROOM P3V3_STBY_VR
J 0
(8150 4325);
PAINT GREEN (8150 4325);
DISPLAY INVISIBLE (8150 4325);
FORCEADD GND..1
(8150 4175);
FORCEPROP 3 LASTPIN (8150 4225) SIG_NAME GND\g
J 0
(8160 4235);
DISPLAY 0.659574 (8160 4235);
PAINT MONO (8160 4235);
DISPLAY INVISIBLE (8160 4235);
FORCEPROP 1 LAST PATH I138
J 0
(8225 4175);
DISPLAY 0.872340 (8225 4175);
PAINT AQUA (8225 4175);
DISPLAY INVISIBLE (8225 4175);
FORCEPROP 1 LAST SIZE 1B
J 0
(8225 4125);
DISPLAY 0.872340 (8225 4125);
PAINT GREEN (8225 4125);
DISPLAY INVISIBLE (8225 4125);
FORCEPROP 1 LAST VOLTAGE 0
J 0
(8150 4175);
PAINT SKYBLUE (8150 4175);
DISPLAY INVISIBLE (8150 4175);
FORCEPROP 2 LAST CDS_LIB mstr_symbols
J 0
(8150 4175);
PAINT MONO (8150 4175);
DISPLAY INVISIBLE (8150 4175);
FORCEPROP 2 LAST ROOM PVPP_KLM_VR
J 0
(7575 4250);
DISPLAY 1.042553 (7575 4250);
PAINT GREEN (7575 4250);
DISPLAY INVISIBLE (7575 4250);
FORCEPROP 2 LAST BOM_COST PVPP_KLM_VR
J 0
(7300 4250);
DISPLAY 1.042553 (7300 4250);
PAINT WHITE (7300 4250);
DISPLAY INVISIBLE (7300 4250);
FORCEPROP 1 LAST BODY_TYPE PLUMBING
J 0
(8105 4132);
DISPLAY 0.340426 (8105 4132);
PAINT GREEN (8105 4132);
DISPLAY INVISIBLE (8105 4132);
FORCEPROP 1 LAST HDL_POWER GND
J 0
(8150 4325);
DISPLAY 0.872340 (8150 4325);
PAINT GREEN (8150 4325);
DISPLAY INVISIBLE (8150 4325);
FORCEADD CAP..1
(8475 4350);
FORCEPROP 1 LAST LOCATION C8E14
J 0
(8525 4450);
DISPLAY 0.617021 (8525 4450);
PAINT AQUA (8525 4450);
FORCEPROP 1 LAST TOLERANCE 10%
J 0
(8525 4300);
DISPLAY 0.617021 (8525 4300);
PAINT SKYBLUE (8525 4300);
FORCEPROP 1 LAST VOLTAGE 16V
J 0
(8525 4350);
DISPLAY 0.617021 (8525 4350);
PAINT SKYBLUE (8525 4350);
FORCEPROP 1 LAST PART_NUMBER D97712-011
J 0
(8525 4200);
DISPLAY 0.617021 (8525 4200);
PAINT BLUE (8525 4200);
FORCEPROP 1 LASTPIN (8475 4450) $PN 1
J 0
(8485 4430);
DISPLAY 0.617021 (8485 4430);
PAINT WHITE (8485 4430);
FORCEPROP 1 LAST MATERIAL X6S
J 0
(8525 4250);
DISPLAY 0.617021 (8525 4250);
PAINT SKYBLUE (8525 4250);
FORCEPROP 1 LASTPIN (8475 4250) $PN 2
J 0
(8485 4230);
DISPLAY 0.617021 (8485 4230);
PAINT WHITE (8485 4230);
FORCEPROP 1 LAST VALUE 1.0UF
J 0
(8525 4400);
DISPLAY 0.617021 (8525 4400);
PAINT SKYBLUE (8525 4400);
FORCEPROP 1 LAST PACK_TYPE 0402
J 0
(8525 4150);
DISPLAY 0.617021 (8525 4150);
PAINT SKYBLUE (8525 4150);
FORCEPROP 0 LAST REUSE_ID 1
J 0
(8525 4550);
DISPLAY 1.042553 (8525 4550);
PAINT ORANGE (8525 4550);
DISPLAY INVISIBLE (8525 4550);
FORCEPROP 0 LAST FIN VR_1P2
J 0
(8525 4650);
PAINT ORANGE (8525 4650);
DISPLAY INVISIBLE (8525 4650);
FORCEPROP 2 LAST CDS_SEC 1
J 0
(8525 4550);
DISPLAY 1.042553 (8525 4550);
PAINT ORANGE (8525 4550);
DISPLAY INVISIBLE (8525 4550);
FORCEPROP 2 LAST $SEC 1
J 0
(8525 4550);
DISPLAY 0.680851 (8525 4550);
PAINT MONO (8525 4550);
DISPLAY INVISIBLE (8525 4550);
FORCEPROP 2 LAST CDS_LOCATION C8E14
J 0
(8525 4450);
DISPLAY 0.617021 (8525 4450);
PAINT AQUA (8525 4450);
DISPLAY INVISIBLE (8525 4450);
FORCEPROP 1 LAST PATH I139
J 0
(8525 4500);
DISPLAY 0.978723 (8525 4500);
PAINT WHITE (8525 4500);
DISPLAY INVISIBLE (8525 4500);
FORCEPROP 2 LAST ROOM P3V3_STBY_VR
J 0
(8475 4350);
PAINT GREEN (8475 4350);
DISPLAY INVISIBLE (8475 4350);
FORCEPROP 2 LAST BOM_COST P3V3_STBY_VR
J 0
(8475 4350);
PAINT WHITE (8475 4350);
DISPLAY INVISIBLE (8475 4350);
FORCEPROP 2 LAST CDS_LIB mstr_discrete
J 0
(8475 4350);
PAINT MONO (8475 4350);
DISPLAY INVISIBLE (8475 4350);
FORCEADD RES..1
(9225 925);
FORCEPROP 1 LAST VALUE 0.0
J 2
(9200 850);
DISPLAY 0.617021 (9200 850);
PAINT SKYBLUE (9200 850);
FORCEPROP 1 LAST MATERIAL CHIP
J 0
(8975 850);
DISPLAY 0.638298 (8975 850);
PAINT SKYBLUE (8975 850);
FORCEPROP 1 LAST TOLERANCE 5%
J 0
(9225 850);
DISPLAY 0.617021 (9225 850);
PAINT SKYBLUE (9225 850);
FORCEPROP 1 LAST WATTAGE 1/16W
J 2
(9275 800);
DISPLAY 0.617021 (9275 800);
PAINT SKYBLUE (9275 800);
FORCEPROP 1 LAST PART_NUMBER G21497-005
J 0
(9125 1025);
DISPLAY 0.617021 (9125 1025);
PAINT BLUE (9125 1025);
FORCEPROP 1 LAST LOCATION R8E38
J 0
(9175 975);
DISPLAY 0.617021 (9175 975);
PAINT AQUA (9175 975);
FORCEPROP 1 LASTPIN (9125 925) $PN 1
J 0
(9137 937);
DISPLAY 0.617021 (9137 937);
PAINT GREEN (9137 937);
FORCEPROP 1 LASTPIN (9325 925) $PN 2
J 0
(9287 937);
DISPLAY 0.617021 (9287 937);
PAINT GREEN (9287 937);
FORCEPROP 1 LAST PACK_TYPE 0402
J 0
(9175 750);
DISPLAY 0.617021 (9175 750);
PAINT SKYBLUE (9175 750);
FORCEPROP 2 LAST CDS_LOCATION R8E38
J 0
(9175 975);
DISPLAY 0.617021 (9175 975);
PAINT AQUA (9175 975);
DISPLAY INVISIBLE (9175 975);
FORCEPROP 2 LAST CDS_SEC 1
J 0
(9175 1125);
PAINT MONO (9175 1125);
DISPLAY INVISIBLE (9175 1125);
FORCEPROP 2 LAST $SEC 1
J 0
(9175 1125);
PAINT MONO (9175 1125);
DISPLAY INVISIBLE (9175 1125);
FORCEPROP 1 LAST PATH I140
J 0
(9175 1075);
DISPLAY 0.978723 (9175 1075);
PAINT WHITE (9175 1075);
DISPLAY INVISIBLE (9175 1075);
FORCEPROP 2 LAST ROOM P3V3_STBY_VR
J 0
(9175 1025);
PAINT ORANGE (9175 1025);
DISPLAY INVISIBLE (9175 1025);
FORCEPROP 2 LAST CDS_LIB mstr_discrete
J 0
(9225 925);
PAINT ORANGE (9225 925);
DISPLAY INVISIBLE (9225 925);
FORCEPROP 2 LAST BOM_COST P3V3_STBY_VR
J 0
(9300 1075);
PAINT MONO (9300 1075);
DISPLAY INVISIBLE (9300 1075);
FORCEADD RES..2
(9475 1100);
FORCEPROP 1 LAST PART_NUMBER G21796-016
J 0
(9515 975);
DISPLAY 0.617021 (9515 975);
PAINT BLUE (9515 975);
FORCEPROP 1 LAST PACK_TYPE 0402
J 0
(9515 925);
DISPLAY 0.617021 (9515 925);
PAINT SKYBLUE (9515 925);
FORCEPROP 1 LAST LOCATION R8E34
J 0
(9520 1225);
DISPLAY 0.617021 (9520 1225);
PAINT AQUA (9520 1225);
FORCEPROP 1 LASTPIN (9475 1000) $PN 2
J 0
(9480 1010);
DISPLAY 0.617021 (9480 1010);
PAINT WHITE (9480 1010);
FORCEPROP 1 LAST MATERIAL CHIP
J 0
(9515 1025);
DISPLAY 0.617021 (9515 1025);
PAINT SKYBLUE (9515 1025);
FORCEPROP 1 LAST WATTAGE 1/16W
J 0
(9515 1075);
DISPLAY 0.617021 (9515 1075);
PAINT SKYBLUE (9515 1075);
FORCEPROP 1 LAST TOLERANCE 1%
J 0
(9520 1125);
DISPLAY 0.617021 (9520 1125);
PAINT SKYBLUE (9520 1125);
FORCEPROP 1 LASTPIN (9475 1200) $PN 1
J 0
(9480 1162);
DISPLAY 0.617021 (9480 1162);
PAINT WHITE (9480 1162);
FORCEPROP 1 LAST VALUE 10.0K
J 0
(9520 1175);
DISPLAY 0.617021 (9520 1175);
PAINT SKYBLUE (9520 1175);
FORCEPROP 2 LAST BOM_COST P3V3_STBY_VR
R 1
J 0
(9175 1150);
DISPLAY 1.042553 (9175 1150);
PAINT WHITE (9175 1150);
DISPLAY INVISIBLE (9175 1150);
FORCEPROP 2 LAST ROOM P3V3_STBY_VR
R 1
J 0
(9275 1150);
DISPLAY 1.042553 (9275 1150);
PAINT GREEN (9275 1150);
DISPLAY INVISIBLE (9275 1150);
FORCEPROP 2 LAST CDS_LIB mstr_discrete
R 1
J 0
(9475 1100);
PAINT MONO (9475 1100);
DISPLAY INVISIBLE (9475 1100);
FORCEPROP 2 LAST CDS_LOCATION R8E34
J 0
(9520 1225);
DISPLAY 0.617021 (9520 1225);
PAINT AQUA (9520 1225);
DISPLAY INVISIBLE (9520 1225);
FORCEPROP 1 LAST PATH I142
J 0
(9525 1275);
DISPLAY 0.978723 (9525 1275);
PAINT WHITE (9525 1275);
DISPLAY INVISIBLE (9525 1275);
FORCEPROP 2 LAST $SEC 1
J 0
(9525 1325);
DISPLAY 0.680851 (9525 1325);
PAINT MONO (9525 1325);
DISPLAY INVISIBLE (9525 1325);
FORCEPROP 0 LAST SPOF TRUE
J 0
(9525 1325);
DISPLAY 1.021277 (9525 1325);
PAINT ORANGE (9525 1325);
DISPLAY INVISIBLE (9525 1325);
FORCEPROP 2 LAST REUSE_ID 7
J 0
(9525 1325);
DISPLAY 1.042553 (9525 1325);
PAINT ORANGE (9525 1325);
DISPLAY INVISIBLE (9525 1325);
FORCEPROP 2 LAST CDS_SEC 1
J 0
(9525 1325);
DISPLAY 1.042553 (9525 1325);
PAINT ORANGE (9525 1325);
DISPLAY INVISIBLE (9525 1325);
FORCEADD RES..2
(9475 1425);
FORCEPROP 1 LAST WATTAGE 1/16W
J 0
(9515 1400);
DISPLAY 0.617021 (9515 1400);
PAINT SKYBLUE (9515 1400);
FORCEPROP 1 LAST PACK_TYPE 0402
J 0
(9640 1350);
DISPLAY 0.617021 (9640 1350);
PAINT SKYBLUE (9640 1350);
FORCEPROP 1 LAST PART_NUMBER G21796-114
J 0
(9515 1300);
DISPLAY 0.617021 (9515 1300);
PAINT BLUE (9515 1300);
FORCEPROP 1 LASTPIN (9475 1325) $PN 2
J 0
(9480 1335);
DISPLAY 0.617021 (9480 1335);
PAINT WHITE (9480 1335);
FORCEPROP 1 LAST MATERIAL CHIP
J 0
(9515 1350);
DISPLAY 0.617021 (9515 1350);
PAINT SKYBLUE (9515 1350);
FORCEPROP 1 LAST TOLERANCE 1%
J 0
(9520 1450);
DISPLAY 0.617021 (9520 1450);
PAINT SKYBLUE (9520 1450);
FORCEPROP 1 LASTPIN (9475 1525) $PN 1
J 0
(9480 1487);
DISPLAY 0.617021 (9480 1487);
PAINT WHITE (9480 1487);
FORCEPROP 1 LAST LOCATION R8E31
J 0
(9520 1550);
DISPLAY 0.617021 (9520 1550);
PAINT AQUA (9520 1550);
FORCEPROP 1 LAST VALUE 23.2K
J 0
(9520 1500);
DISPLAY 0.617021 (9520 1500);
PAINT SKYBLUE (9520 1500);
FORCEPROP 2 LAST CDS_LIB mstr_discrete
J 0
(9475 1425);
PAINT MONO (9475 1425);
DISPLAY INVISIBLE (9475 1425);
FORCEPROP 2 LAST ROOM P3V3_STBY_VR
J 0
(9520 1580);
PAINT GREEN (9520 1580);
DISPLAY INVISIBLE (9520 1580);
FORCEPROP 1 LAST PATH I143
J 0
(9525 1600);
DISPLAY 0.978723 (9525 1600);
PAINT WHITE (9525 1600);
DISPLAY INVISIBLE (9525 1600);
FORCEPROP 2 LAST CDS_LOCATION R8E31
J 0
(9520 1550);
DISPLAY 0.617021 (9520 1550);
PAINT AQUA (9520 1550);
DISPLAY INVISIBLE (9520 1550);
FORCEPROP 2 LAST $SEC 1
J 0
(9525 1650);
DISPLAY 0.680851 (9525 1650);
PAINT MONO (9525 1650);
DISPLAY INVISIBLE (9525 1650);
FORCEPROP 2 LAST CDS_SEC 1
J 0
(9525 1650);
DISPLAY 1.042553 (9525 1650);
PAINT ORANGE (9525 1650);
DISPLAY INVISIBLE (9525 1650);
FORCEPROP 2 LAST REUSE_ID 9
J 0
(9525 1650);
DISPLAY 1.042553 (9525 1650);
PAINT ORANGE (9525 1650);
DISPLAY INVISIBLE (9525 1650);
FORCEPROP 2 LAST BOM_COST P3V3_STBY_VR
J 0
(9520 1605);
DISPLAY 1.042553 (9520 1605);
PAINT WHITE (9520 1605);
DISPLAY INVISIBLE (9520 1605);
FORCEPROP 0 LAST SPOF TRUE
J 0
(9525 1650);
DISPLAY 1.021277 (9525 1650);
PAINT ORANGE (9525 1650);
DISPLAY INVISIBLE (9525 1650);
FORCEADD RES..1
R 5
(9525 1800);
FORCEPROP 1 LASTPIN (9525 1700) $PN 2
J 0
(9537 1738);
DISPLAY 0.617021 (9537 1738);
PAINT ORANGE (9537 1738);
FORCEPROP 1 LAST PACK_TYPE 0402
J 0
(9550 1650);
DISPLAY 0.617021 (9550 1650);
PAINT SKYBLUE (9550 1650);
FORCEPROP 1 LAST MATERIAL CHIP
J 0
(9550 1700);
DISPLAY 0.617021 (9550 1700);
PAINT SKYBLUE (9550 1700);
FORCEPROP 1 LASTPIN (9525 1900) $PN 1
J 0
(9537 1888);
DISPLAY 0.617021 (9537 1888);
PAINT ORANGE (9537 1888);
FORCEPROP 1 LAST PART_NUMBER G21497-005
J 0
(9550 1600);
DISPLAY 0.617021 (9550 1600);
PAINT BLUE (9550 1600);
FORCEPROP 1 LAST WATTAGE 1/16W
J 0
(9575 1750);
DISPLAY 0.617021 (9575 1750);
PAINT SKYBLUE (9575 1750);
FORCEPROP 1 LAST TOLERANCE 5%
J 0
(9575 1800);
DISPLAY 0.617021 (9575 1800);
PAINT SKYBLUE (9575 1800);
FORCEPROP 1 LAST VALUE 0.0
J 0
(9575 1850);
DISPLAY 0.617021 (9575 1850);
PAINT SKYBLUE (9575 1850);
FORCEPROP 1 LAST LOCATION R8E25
J 0
(9575 1900);
DISPLAY 0.617021 (9575 1900);
PAINT AQUA (9575 1900);
FORCEPROP 2 LAST CDS_LOCATION R8E25
J 0
(9625 1750);
DISPLAY 0.617021 (9625 1750);
PAINT AQUA (9625 1750);
DISPLAY INVISIBLE (9625 1750);
FORCEPROP 2 LAST SEC 1
J 0
(9600 1950);
DISPLAY 0.680851 (9600 1950);
PAINT MONO (9600 1950);
DISPLAY INVISIBLE (9600 1950);
FORCEPROP 0 LAST SPOF TRUE
J 0
(9550 1925);
DISPLAY 1.021277 (9550 1925);
PAINT ORANGE (9550 1925);
DISPLAY INVISIBLE (9550 1925);
FORCEPROP 2 LAST SEC_TYPE 0402
J 0
(9600 1950);
DISPLAY 1.021277 (9600 1950);
PAINT ORANGE (9600 1950);
DISPLAY INVISIBLE (9600 1950);
FORCEPROP 2 LAST CDS_LIB mstr_discrete
J 0
(9525 1800);
PAINT ORANGE (9525 1800);
DISPLAY INVISIBLE (9525 1800);
FORCEPROP 1 LAST PATH I144
R 3
J 0
(9675 1850);
DISPLAY 0.978723 (9675 1850);
PAINT WHITE (9675 1850);
DISPLAY INVISIBLE (9675 1850);
FORCEPROP 2 LAST ROOM PVPP_KLM_VR
R 3
J 0
(9675 1850);
DISPLAY 1.659574 (9675 1850);
PAINT GREEN (9675 1850);
DISPLAY INVISIBLE (9675 1850);
FORCEADD GND..1
(10175 1625);
FORCEPROP 3 LASTPIN (10175 1675) SIG_NAME GND\g
J 0
(10185 1685);
DISPLAY 0.659574 (10185 1685);
PAINT MONO (10185 1685);
DISPLAY INVISIBLE (10185 1685);
FORCEPROP 2 LAST BOM_COST PVPP_KLM_VR
J 0
(9325 1700);
DISPLAY 1.042553 (9325 1700);
PAINT WHITE (9325 1700);
DISPLAY INVISIBLE (9325 1700);
FORCEPROP 2 LAST ROOM PVPP_KLM_VR
J 0
(9600 1700);
DISPLAY 1.042553 (9600 1700);
PAINT GREEN (9600 1700);
DISPLAY INVISIBLE (9600 1700);
FORCEPROP 2 LAST CDS_LIB mstr_symbols
J 0
(10175 1625);
PAINT MONO (10175 1625);
DISPLAY INVISIBLE (10175 1625);
FORCEPROP 1 LAST VOLTAGE 0
J 0
(10175 1625);
PAINT SKYBLUE (10175 1625);
DISPLAY INVISIBLE (10175 1625);
FORCEPROP 1 LAST PATH I145
J 0
(10250 1625);
DISPLAY 0.872340 (10250 1625);
PAINT AQUA (10250 1625);
DISPLAY INVISIBLE (10250 1625);
FORCEPROP 1 LAST SIZE 1B
J 0
(10250 1575);
DISPLAY 0.872340 (10250 1575);
PAINT AQUA (10250 1575);
DISPLAY INVISIBLE (10250 1575);
FORCEPROP 1 LAST BODY_TYPE PLUMBING
J 0
(10130 1582);
DISPLAY 0.340426 (10130 1582);
PAINT GREEN (10130 1582);
DISPLAY INVISIBLE (10130 1582);
FORCEPROP 1 LAST HDL_POWER GND
J 0
(10175 1775);
DISPLAY 0.872340 (10175 1775);
PAINT GREEN (10175 1775);
DISPLAY INVISIBLE (10175 1775);
FORCEADD RES..1
(10475 1725);
FORCEPROP 1 LAST PART_NUMBER G21497-005
J 0
(10350 1675);
DISPLAY 0.617021 (10350 1675);
PAINT BLUE (10350 1675);
FORCEPROP 1 LAST VALUE 0.0
J 2
(10450 1625);
DISPLAY 0.617021 (10450 1625);
PAINT SKYBLUE (10450 1625);
FORCEPROP 1 LAST PACK_TYPE 0402
J 0
(10400 1525);
DISPLAY 0.617021 (10400 1525);
PAINT SKYBLUE (10400 1525);
FORCEPROP 1 LAST WATTAGE 1/16W
J 2
(10475 1575);
DISPLAY 0.617021 (10475 1575);
PAINT SKYBLUE (10475 1575);
FORCEPROP 1 LASTPIN (10375 1725) $PN 1
J 0
(10387 1737);
DISPLAY 0.617021 (10387 1737);
PAINT WHITE (10387 1737);
FORCEPROP 1 LAST MATERIAL CHIP
J 0
(10475 1575);
DISPLAY 0.617021 (10475 1575);
PAINT SKYBLUE (10475 1575);
FORCEPROP 1 LAST LOCATION R8F11
J 0
(10425 1775);
DISPLAY 0.617021 (10425 1775);
PAINT AQUA (10425 1775);
FORCEPROP 1 LASTPIN (10575 1725) $PN 2
J 0
(10537 1737);
DISPLAY 0.617021 (10537 1737);
PAINT WHITE (10537 1737);
FORCEPROP 1 LAST TOLERANCE 5%
J 0
(10475 1625);
DISPLAY 0.617021 (10475 1625);
PAINT SKYBLUE (10475 1625);
FORCEPROP 2 LAST CDS_LIB mstr_discrete
J 0
(10475 1725);
PAINT MONO (10475 1725);
DISPLAY INVISIBLE (10475 1725);
FORCEPROP 2 LAST CDS_LOCATION R8F11
J 0
(10425 1775);
DISPLAY 0.617021 (10425 1775);
PAINT AQUA (10425 1775);
DISPLAY INVISIBLE (10425 1775);
FORCEPROP 2 LAST CDS_SEC 1
J 0
(10435 1910);
PAINT MONO (10435 1910);
DISPLAY INVISIBLE (10435 1910);
FORCEPROP 2 LAST $SEC 1
J 0
(10440 1930);
PAINT MONO (10440 1930);
DISPLAY INVISIBLE (10440 1930);
FORCEPROP 1 LAST PATH I146
J 0
(10425 1875);
DISPLAY 0.978723 (10425 1875);
PAINT WHITE (10425 1875);
DISPLAY INVISIBLE (10425 1875);
FORCEPROP 2 LAST ROOM P3V3_STBY_VR
J 0
(10425 1800);
PAINT GREEN (10425 1800);
DISPLAY INVISIBLE (10425 1800);
FORCEADD GND..1
(9650 3150);
FORCEPROP 3 LASTPIN (9650 3200) SIG_NAME GND\g
J 0
(9660 3210);
DISPLAY 0.659574 (9660 3210);
PAINT MONO (9660 3210);
DISPLAY INVISIBLE (9660 3210);
FORCEPROP 2 LAST BOM_COST PVPP_KLM_VR
J 0
(8800 3225);
DISPLAY 1.042553 (8800 3225);
PAINT WHITE (8800 3225);
DISPLAY INVISIBLE (8800 3225);
FORCEPROP 1 LAST SIZE 1B
J 0
(9725 3100);
DISPLAY 0.872340 (9725 3100);
PAINT AQUA (9725 3100);
DISPLAY INVISIBLE (9725 3100);
FORCEPROP 2 LAST ROOM PVPP_KLM_VR
J 0
(9075 3225);
DISPLAY 1.042553 (9075 3225);
PAINT GREEN (9075 3225);
DISPLAY INVISIBLE (9075 3225);
FORCEPROP 1 LAST VOLTAGE 0
J 0
(9650 3150);
PAINT SKYBLUE (9650 3150);
DISPLAY INVISIBLE (9650 3150);
FORCEPROP 2 LAST CDS_LIB mstr_symbols
J 0
(9650 3150);
PAINT MONO (9650 3150);
DISPLAY INVISIBLE (9650 3150);
FORCEPROP 1 LAST PATH I147
J 0
(9725 3150);
DISPLAY 0.872340 (9725 3150);
PAINT AQUA (9725 3150);
DISPLAY INVISIBLE (9725 3150);
FORCEPROP 1 LAST BODY_TYPE PLUMBING
J 0
(9605 3107);
DISPLAY 0.340426 (9605 3107);
PAINT GREEN (9605 3107);
DISPLAY INVISIBLE (9605 3107);
FORCEPROP 1 LAST HDL_POWER GND
J 0
(9650 3300);
DISPLAY 0.872340 (9650 3300);
PAINT GREEN (9650 3300);
DISPLAY INVISIBLE (9650 3300);
FORCEADD RES..2
(9750 3550);
FORCEPROP 1 LAST WATTAGE 1/16W
J 0
(9890 3450);
DISPLAY 0.617021 (9890 3450);
PAINT SKYBLUE (9890 3450);
FORCEPROP 1 LAST TOLERANCE 5%
J 0
(9895 3500);
DISPLAY 0.617021 (9895 3500);
PAINT SKYBLUE (9895 3500);
FORCEPROP 1 LAST VALUE 2.2
J 0
(9895 3550);
DISPLAY 0.617021 (9895 3550);
PAINT SKYBLUE (9895 3550);
FORCEPROP 1 LAST PART_NUMBER G21497-016
J 0
(10040 3550);
DISPLAY 0.617021 (10040 3550);
PAINT BLUE (10040 3550);
FORCEPROP 1 LASTPIN (9750 3650) $PN 1
J 0
(9755 3612);
DISPLAY 0.617021 (9755 3612);
PAINT WHITE (9755 3612);
FORCEPROP 1 LASTPIN (9750 3450) $PN 2
J 0
(9755 3460);
DISPLAY 0.617021 (9755 3460);
PAINT WHITE (9755 3460);
FORCEPROP 1 LAST PACK_TYPE 0402
J 0
(10040 3600);
DISPLAY 0.617021 (10040 3600);
PAINT SKYBLUE (10040 3600);
FORCEPROP 1 LAST LOCATION R8F3
J 0
(9895 3600);
DISPLAY 0.617021 (9895 3600);
PAINT AQUA (9895 3600);
FORCEPROP 1 LAST MATERIAL EMPTY
J 0
(10040 3500);
DISPLAY 0.617021 (10040 3500);
PAINT RED (10040 3500);
FORCEPROP 2 LAST BOM_COST P3V3_STBY_VR
J 0
(9800 3725);
DISPLAY 1.042553 (9800 3725);
PAINT WHITE (9800 3725);
DISPLAY INVISIBLE (9800 3725);
FORCEPROP 2 LAST REUSE_ID 29
J 0
(9800 3775);
DISPLAY 1.042553 (9800 3775);
PAINT ORANGE (9800 3775);
DISPLAY INVISIBLE (9800 3775);
FORCEPROP 2 LAST CDS_SEC 1
J 0
(9800 3775);
DISPLAY 1.042553 (9800 3775);
PAINT ORANGE (9800 3775);
DISPLAY INVISIBLE (9800 3775);
FORCEPROP 2 LAST $SEC 1
J 0
(9800 3775);
DISPLAY 0.680851 (9800 3775);
PAINT MONO (9800 3775);
DISPLAY INVISIBLE (9800 3775);
FORCEPROP 1 LAST PATH I148
J 0
(9800 3725);
DISPLAY 0.978723 (9800 3725);
PAINT WHITE (9800 3725);
DISPLAY INVISIBLE (9800 3725);
FORCEPROP 2 LAST ROOM P3V3_STBY_VR
J 0
(9800 3700);
PAINT GREEN (9800 3700);
DISPLAY INVISIBLE (9800 3700);
FORCEPROP 2 LAST CDS_LOCATION R8F3
J 0
(9795 3650);
DISPLAY 0.617021 (9795 3650);
PAINT AQUA (9795 3650);
DISPLAY INVISIBLE (9795 3650);
FORCEPROP 2 LAST CDS_LIB mstr_discrete
J 0
(9750 3550);
PAINT MONO (9750 3550);
DISPLAY INVISIBLE (9750 3550);
FORCEADD GND..1
(9750 3350);
FORCEPROP 3 LASTPIN (9750 3400) SIG_NAME GND\g
J 0
(9760 3410);
DISPLAY 0.659574 (9760 3410);
PAINT MONO (9760 3410);
DISPLAY INVISIBLE (9760 3410);
FORCEPROP 1 LAST SIZE 1B
J 0
(9825 3375);
DISPLAY 0.893617 (9825 3375);
PAINT GREEN (9825 3375);
DISPLAY INVISIBLE (9825 3375);
FORCEPROP 1 LAST PATH I149
J 0
(9825 3350);
DISPLAY 0.872340 (9825 3350);
PAINT AQUA (9825 3350);
DISPLAY INVISIBLE (9825 3350);
FORCEPROP 1 LAST VOLTAGE 0
J 0
(9750 3425);
PAINT SKYBLUE (9750 3425);
DISPLAY INVISIBLE (9750 3425);
FORCEPROP 2 LAST CDS_LIB mstr_symbols
J 0
(9750 3425);
PAINT MONO (9750 3425);
DISPLAY INVISIBLE (9750 3425);
FORCEPROP 2 LAST ROOM PVPP_KLM_VR
J 0
(9100 3500);
PAINT GREEN (9100 3500);
DISPLAY INVISIBLE (9100 3500);
FORCEPROP 2 LAST BOM_COST PVPP_KLM_VR
J 0
(8850 3500);
DISPLAY 1.042553 (8850 3500);
PAINT WHITE (8850 3500);
DISPLAY INVISIBLE (8850 3500);
FORCEPROP 1 LAST BODY_TYPE PLUMBING
J 0
(9705 3307);
DISPLAY 0.340426 (9705 3307);
PAINT GREEN (9705 3307);
DISPLAY INVISIBLE (9705 3307);
FORCEPROP 1 LAST HDL_POWER GND
J 0
(9750 3575);
DISPLAY 0.893617 (9750 3575);
PAINT GREEN (9750 3575);
DISPLAY INVISIBLE (9750 3575);
FORCEADD GND..1
(10750 3550);
FORCEPROP 3 LASTPIN (10750 3600) SIG_NAME GND\g
J 0
(10760 3610);
DISPLAY 0.659574 (10760 3610);
PAINT MONO (10760 3610);
DISPLAY INVISIBLE (10760 3610);
FORCEPROP 2 LAST BOM_COST PVPP_KLM_VR
J 0
(9900 3625);
DISPLAY 1.042553 (9900 3625);
PAINT WHITE (9900 3625);
DISPLAY INVISIBLE (9900 3625);
FORCEPROP 2 LAST ROOM PVPP_KLM_VR
J 0
(10175 3625);
DISPLAY 1.042553 (10175 3625);
PAINT GREEN (10175 3625);
DISPLAY INVISIBLE (10175 3625);
FORCEPROP 1 LAST SIZE 1B
J 0
(10825 3500);
DISPLAY 0.872340 (10825 3500);
PAINT GREEN (10825 3500);
DISPLAY INVISIBLE (10825 3500);
FORCEPROP 1 LAST VOLTAGE 0
J 0
(10750 3550);
PAINT SKYBLUE (10750 3550);
DISPLAY INVISIBLE (10750 3550);
FORCEPROP 1 LAST PATH I151
J 0
(10825 3550);
DISPLAY 0.872340 (10825 3550);
PAINT AQUA (10825 3550);
DISPLAY INVISIBLE (10825 3550);
FORCEPROP 2 LAST CDS_LIB mstr_symbols
J 0
(10750 3550);
PAINT MONO (10750 3550);
DISPLAY INVISIBLE (10750 3550);
FORCEPROP 1 LAST BODY_TYPE PLUMBING
J 0
(10705 3507);
DISPLAY 0.340426 (10705 3507);
PAINT GREEN (10705 3507);
DISPLAY INVISIBLE (10705 3507);
FORCEPROP 1 LAST HDL_POWER GND
J 0
(10750 3700);
DISPLAY 0.872340 (10750 3700);
PAINT GREEN (10750 3700);
DISPLAY INVISIBLE (10750 3700);
FORCEADD RES..2
(10750 3800);
FORCEPROP 1 LAST LOCATION R2T4
J 0
(10795 3900);
DISPLAY 0.617021 (10795 3900);
PAINT AQUA (10795 3900);
FORCEPROP 1 LAST WATTAGE 1/16W
J 0
(10790 3750);
DISPLAY 0.617021 (10790 3750);
PAINT SKYBLUE (10790 3750);
FORCEPROP 1 LAST TOLERANCE 0.1%
J 0
(10795 3800);
DISPLAY 0.617021 (10795 3800);
PAINT SKYBLUE (10795 3800);
FORCEPROP 1 LASTPIN (10750 3900) $PN 1
J 0
(10755 3862);
DISPLAY 0.617021 (10755 3862);
PAINT WHITE (10755 3862);
FORCEPROP 1 LAST MATERIAL CHIP
J 0
(10790 3700);
DISPLAY 0.617021 (10790 3700);
PAINT SKYBLUE (10790 3700);
FORCEPROP 1 LAST VALUE 1.0K
J 0
(10795 3850);
DISPLAY 0.617021 (10795 3850);
PAINT SKYBLUE (10795 3850);
FORCEPROP 1 LAST PACK_TYPE 0402
J 0
(10790 3600);
DISPLAY 0.617021 (10790 3600);
PAINT SKYBLUE (10790 3600);
FORCEPROP 1 LAST PART_NUMBER G85996-004
J 0
(10790 3650);
DISPLAY 0.617021 (10790 3650);
PAINT BLUE (10790 3650);
FORCEPROP 1 LASTPIN (10750 3700) $PN 2
J 0
(10755 3710);
DISPLAY 0.617021 (10755 3710);
PAINT WHITE (10755 3710);
FORCEPROP 2 LAST REUSE_ID 34
J 0
(10800 4025);
DISPLAY 1.042553 (10800 4025);
PAINT ORANGE (10800 4025);
DISPLAY INVISIBLE (10800 4025);
FORCEPROP 2 LAST CDS_SEC 1
J 0
(10800 4025);
DISPLAY 1.042553 (10800 4025);
PAINT ORANGE (10800 4025);
DISPLAY INVISIBLE (10800 4025);
FORCEPROP 2 LAST $SEC 1
J 0
(10800 4025);
DISPLAY 0.680851 (10800 4025);
PAINT MONO (10800 4025);
DISPLAY INVISIBLE (10800 4025);
FORCEPROP 2 LAST BOM_COST P3V3_STBY_VR
J 0
(10795 3980);
DISPLAY 1.042553 (10795 3980);
PAINT WHITE (10795 3980);
DISPLAY INVISIBLE (10795 3980);
FORCEPROP 2 LAST CDS_LOCATION R2T4
J 0
(10795 3925);
DISPLAY 0.617021 (10795 3925);
PAINT AQUA (10795 3925);
DISPLAY INVISIBLE (10795 3925);
FORCEPROP 1 LAST PATH I152
J 0
(10800 3975);
DISPLAY 0.978723 (10800 3975);
PAINT WHITE (10800 3975);
DISPLAY INVISIBLE (10800 3975);
FORCEPROP 2 LAST ROOM P3V3_STBY_VR
J 0
(10795 3955);
PAINT GREEN (10795 3955);
DISPLAY INVISIBLE (10795 3955);
FORCEPROP 2 LAST CDS_LIB mstr_discrete
J 0
(10750 3800);
PAINT MONO (10750 3800);
DISPLAY INVISIBLE (10750 3800);
FORCEADD GND..1
(11100 3550);
FORCEPROP 3 LASTPIN (11100 3600) SIG_NAME GND\g
J 0
(11110 3610);
DISPLAY 0.659574 (11110 3610);
PAINT MONO (11110 3610);
DISPLAY INVISIBLE (11110 3610);
FORCEPROP 1 LAST PATH I153
J 0
(11175 3550);
DISPLAY 0.872340 (11175 3550);
PAINT AQUA (11175 3550);
DISPLAY INVISIBLE (11175 3550);
FORCEPROP 1 LAST SIZE 1B
J 0
(11175 3500);
DISPLAY 0.872340 (11175 3500);
PAINT GREEN (11175 3500);
DISPLAY INVISIBLE (11175 3500);
FORCEPROP 2 LAST CDS_LIB mstr_symbols
J 0
(11100 3550);
PAINT MONO (11100 3550);
DISPLAY INVISIBLE (11100 3550);
FORCEPROP 1 LAST VOLTAGE 0
J 0
(11100 3550);
PAINT SKYBLUE (11100 3550);
DISPLAY INVISIBLE (11100 3550);
FORCEPROP 2 LAST ROOM PVPP_KLM_VR
J 0
(10525 3625);
DISPLAY 1.042553 (10525 3625);
PAINT GREEN (10525 3625);
DISPLAY INVISIBLE (10525 3625);
FORCEPROP 2 LAST BOM_COST PVPP_KLM_VR
J 0
(10250 3625);
DISPLAY 1.042553 (10250 3625);
PAINT WHITE (10250 3625);
DISPLAY INVISIBLE (10250 3625);
FORCEPROP 1 LAST BODY_TYPE PLUMBING
J 0
(11055 3507);
DISPLAY 0.340426 (11055 3507);
PAINT GREEN (11055 3507);
DISPLAY INVISIBLE (11055 3507);
FORCEPROP 1 LAST HDL_POWER GND
J 0
(11100 3700);
DISPLAY 0.872340 (11100 3700);
PAINT GREEN (11100 3700);
DISPLAY INVISIBLE (11100 3700);
FORCEADD GND..1
(11500 3550);
FORCEPROP 3 LASTPIN (11500 3600) SIG_NAME GND\g
J 0
(11510 3610);
DISPLAY 0.659574 (11510 3610);
PAINT MONO (11510 3610);
DISPLAY INVISIBLE (11510 3610);
FORCEPROP 1 LAST VOLTAGE 0
J 0
(11500 3550);
PAINT SKYBLUE (11500 3550);
DISPLAY INVISIBLE (11500 3550);
FORCEPROP 1 LAST SIZE 1B
J 0
(11575 3500);
DISPLAY 0.872340 (11575 3500);
PAINT GREEN (11575 3500);
DISPLAY INVISIBLE (11575 3500);
FORCEPROP 2 LAST CDS_LIB mstr_symbols
J 0
(11500 3550);
PAINT MONO (11500 3550);
DISPLAY INVISIBLE (11500 3550);
FORCEPROP 1 LAST PATH I156
J 0
(11575 3550);
DISPLAY 0.872340 (11575 3550);
PAINT AQUA (11575 3550);
DISPLAY INVISIBLE (11575 3550);
FORCEPROP 2 LAST ROOM PVPP_KLM_VR
J 0
(10925 3625);
DISPLAY 1.042553 (10925 3625);
PAINT GREEN (10925 3625);
DISPLAY INVISIBLE (10925 3625);
FORCEPROP 2 LAST BOM_COST PVPP_KLM_VR
J 0
(10650 3625);
DISPLAY 1.042553 (10650 3625);
PAINT WHITE (10650 3625);
DISPLAY INVISIBLE (10650 3625);
FORCEPROP 1 LAST BODY_TYPE PLUMBING
J 0
(11455 3507);
DISPLAY 0.340426 (11455 3507);
PAINT GREEN (11455 3507);
DISPLAY INVISIBLE (11455 3507);
FORCEPROP 1 LAST HDL_POWER GND
J 0
(11500 3700);
DISPLAY 0.872340 (11500 3700);
PAINT GREEN (11500 3700);
DISPLAY INVISIBLE (11500 3700);
FORCEADD GND..1
(11950 3600);
FORCEPROP 3 LASTPIN (11950 3650) SIG_NAME GND\g
J 0
(11960 3660);
DISPLAY 0.659574 (11960 3660);
PAINT MONO (11960 3660);
DISPLAY INVISIBLE (11960 3660);
FORCEPROP 2 LAST BOM_COST PVPP_KLM_VR
J 0
(11100 3675);
DISPLAY 1.042553 (11100 3675);
PAINT WHITE (11100 3675);
DISPLAY INVISIBLE (11100 3675);
FORCEPROP 2 LAST ROOM PVPP_KLM_VR
J 0
(11375 3675);
DISPLAY 1.042553 (11375 3675);
PAINT GREEN (11375 3675);
DISPLAY INVISIBLE (11375 3675);
FORCEPROP 1 LAST SIZE 1B
J 0
(12025 3550);
DISPLAY 0.872340 (12025 3550);
PAINT GREEN (12025 3550);
DISPLAY INVISIBLE (12025 3550);
FORCEPROP 1 LAST PATH I157
J 0
(12025 3600);
DISPLAY 0.872340 (12025 3600);
PAINT AQUA (12025 3600);
DISPLAY INVISIBLE (12025 3600);
FORCEPROP 2 LAST CDS_LIB mstr_symbols
J 0
(11950 3600);
PAINT MONO (11950 3600);
DISPLAY INVISIBLE (11950 3600);
FORCEPROP 1 LAST VOLTAGE 0
J 0
(11950 3600);
PAINT SKYBLUE (11950 3600);
DISPLAY INVISIBLE (11950 3600);
FORCEPROP 1 LAST BODY_TYPE PLUMBING
J 0
(11905 3557);
DISPLAY 0.340426 (11905 3557);
PAINT GREEN (11905 3557);
DISPLAY INVISIBLE (11905 3557);
FORCEPROP 1 LAST HDL_POWER GND
J 0
(11950 3750);
DISPLAY 0.872340 (11950 3750);
PAINT GREEN (11950 3750);
DISPLAY INVISIBLE (11950 3750);
FORCEADD CAP..1
(11950 3875);
FORCEPROP 1 LAST PART_NUMBER C95333-008
J 0
(12000 3725);
DISPLAY 0.617021 (12000 3725);
PAINT BLUE (12000 3725);
FORCEPROP 1 LAST MATERIAL X6S
J 0
(12000 3775);
DISPLAY 0.617021 (12000 3775);
PAINT SKYBLUE (12000 3775);
FORCEPROP 1 LAST PACK_TYPE 0805
J 0
(12000 3675);
DISPLAY 0.617021 (12000 3675);
PAINT SKYBLUE (12000 3675);
FORCEPROP 1 LAST VOLTAGE 6.3V
J 0
(12000 3875);
DISPLAY 0.617021 (12000 3875);
PAINT SKYBLUE (12000 3875);
FORCEPROP 1 LAST VALUE 22UF
J 0
(12000 3925);
DISPLAY 0.617021 (12000 3925);
PAINT SKYBLUE (12000 3925);
FORCEPROP 1 LAST LOCATION C2T7
J 0
(12000 3975);
DISPLAY 0.617021 (12000 3975);
PAINT AQUA (12000 3975);
FORCEPROP 1 LAST TOLERANCE 20%
J 0
(12000 3825);
DISPLAY 0.617021 (12000 3825);
PAINT SKYBLUE (12000 3825);
FORCEPROP 1 LASTPIN (11950 3975) $PN 1
J 0
(11960 3955);
DISPLAY 0.617021 (11960 3955);
PAINT WHITE (11960 3955);
FORCEPROP 1 LASTPIN (11950 3775) $PN 2
J 0
(11960 3755);
DISPLAY 0.617021 (11960 3755);
PAINT WHITE (11960 3755);
FORCEPROP 2 LAST ROOM P3V3_STBY_VR
J 0
(11950 3875);
PAINT GREEN (11950 3875);
DISPLAY INVISIBLE (11950 3875);
FORCEPROP 2 LAST BOM_COST P3V3_STBY_VR
J 0
(11950 3875);
PAINT WHITE (11950 3875);
DISPLAY INVISIBLE (11950 3875);
FORCEPROP 2 LAST CDS_LIB mstr_discrete
J 0
(11950 3875);
PAINT MONO (11950 3875);
DISPLAY INVISIBLE (11950 3875);
FORCEPROP 1 LAST PATH I158
J 0
(12000 4025);
DISPLAY 0.978723 (12000 4025);
PAINT WHITE (12000 4025);
DISPLAY INVISIBLE (12000 4025);
FORCEPROP 2 LAST CDS_LOCATION C2T7
J 0
(12000 3975);
DISPLAY 0.617021 (12000 3975);
PAINT AQUA (12000 3975);
DISPLAY INVISIBLE (12000 3975);
FORCEPROP 2 LAST $SEC 1
J 0
(12000 4075);
DISPLAY 0.680851 (12000 4075);
PAINT MONO (12000 4075);
DISPLAY INVISIBLE (12000 4075);
FORCEPROP 2 LAST CDS_SEC 1
J 0
(12000 4075);
DISPLAY 1.042553 (12000 4075);
PAINT ORANGE (12000 4075);
DISPLAY INVISIBLE (12000 4075);
FORCEPROP 2 LAST REUSE_ID 33
J 0
(12000 4075);
DISPLAY 1.042553 (12000 4075);
PAINT ORANGE (12000 4075);
DISPLAY INVISIBLE (12000 4075);
FORCEADD GND..1
(12175 3600);
FORCEPROP 3 LASTPIN (12175 3650) SIG_NAME GND\g
J 0
(12185 3660);
DISPLAY 0.659574 (12185 3660);
PAINT MONO (12185 3660);
DISPLAY INVISIBLE (12185 3660);
FORCEPROP 2 LAST BOM_COST PVPP_KLM_VR
J 0
(11325 3675);
DISPLAY 1.042553 (11325 3675);
PAINT WHITE (11325 3675);
DISPLAY INVISIBLE (11325 3675);
FORCEPROP 2 LAST ROOM PVPP_KLM_VR
J 0
(11600 3675);
DISPLAY 1.042553 (11600 3675);
PAINT GREEN (11600 3675);
DISPLAY INVISIBLE (11600 3675);
FORCEPROP 1 LAST SIZE 1B
J 0
(12250 3550);
DISPLAY 0.872340 (12250 3550);
PAINT GREEN (12250 3550);
DISPLAY INVISIBLE (12250 3550);
FORCEPROP 1 LAST VOLTAGE 0
J 0
(12175 3600);
PAINT SKYBLUE (12175 3600);
DISPLAY INVISIBLE (12175 3600);
FORCEPROP 2 LAST CDS_LIB mstr_symbols
J 0
(12175 3600);
PAINT MONO (12175 3600);
DISPLAY INVISIBLE (12175 3600);
FORCEPROP 1 LAST PATH I159
J 0
(12250 3600);
DISPLAY 0.872340 (12250 3600);
PAINT AQUA (12250 3600);
DISPLAY INVISIBLE (12250 3600);
FORCEPROP 1 LAST BODY_TYPE PLUMBING
J 0
(12130 3557);
DISPLAY 0.340426 (12130 3557);
PAINT GREEN (12130 3557);
DISPLAY INVISIBLE (12130 3557);
FORCEPROP 1 LAST HDL_POWER GND
J 0
(12175 3750);
DISPLAY 0.872340 (12175 3750);
PAINT GREEN (12175 3750);
DISPLAY INVISIBLE (12175 3750);
FORCEADD CAP..1
(12175 3875);
FORCEPROP 1 LAST MATERIAL X6S
J 0
(12225 3775);
DISPLAY 0.617021 (12225 3775);
PAINT SKYBLUE (12225 3775);
FORCEPROP 1 LAST PART_NUMBER C95333-008
J 0
(12225 3725);
DISPLAY 0.617021 (12225 3725);
PAINT BLUE (12225 3725);
FORCEPROP 1 LAST PACK_TYPE 0805
J 0
(12225 3675);
DISPLAY 0.617021 (12225 3675);
PAINT SKYBLUE (12225 3675);
FORCEPROP 1 LAST VOLTAGE 6.3V
J 0
(12225 3875);
DISPLAY 0.617021 (12225 3875);
PAINT SKYBLUE (12225 3875);
FORCEPROP 1 LAST TOLERANCE 20%
J 0
(12225 3825);
DISPLAY 0.617021 (12225 3825);
PAINT SKYBLUE (12225 3825);
FORCEPROP 1 LAST VALUE 22UF
J 0
(12225 3925);
DISPLAY 0.617021 (12225 3925);
PAINT SKYBLUE (12225 3925);
FORCEPROP 1 LAST LOCATION C2T6
J 0
(12225 3975);
DISPLAY 0.617021 (12225 3975);
PAINT AQUA (12225 3975);
FORCEPROP 1 LASTPIN (12175 3975) $PN 1
J 0
(12185 3955);
DISPLAY 0.617021 (12185 3955);
PAINT WHITE (12185 3955);
FORCEPROP 1 LASTPIN (12175 3775) $PN 2
J 0
(12185 3755);
DISPLAY 0.617021 (12185 3755);
PAINT WHITE (12185 3755);
FORCEPROP 2 LAST CDS_SEC 1
J 0
(12225 4075);
DISPLAY 1.042553 (12225 4075);
PAINT ORANGE (12225 4075);
DISPLAY INVISIBLE (12225 4075);
FORCEPROP 2 LAST REUSE_ID 33
J 0
(12225 4075);
DISPLAY 1.042553 (12225 4075);
PAINT ORANGE (12225 4075);
DISPLAY INVISIBLE (12225 4075);
FORCEPROP 2 LAST $SEC 1
J 0
(12225 4075);
DISPLAY 0.680851 (12225 4075);
PAINT MONO (12225 4075);
DISPLAY INVISIBLE (12225 4075);
FORCEPROP 1 LAST PATH I160
J 0
(12225 4025);
DISPLAY 0.978723 (12225 4025);
PAINT WHITE (12225 4025);
DISPLAY INVISIBLE (12225 4025);
FORCEPROP 2 LAST CDS_LOCATION C2T6
J 0
(12225 3975);
DISPLAY 0.617021 (12225 3975);
PAINT AQUA (12225 3975);
DISPLAY INVISIBLE (12225 3975);
FORCEPROP 2 LAST BOM_COST P3V3_STBY_VR
J 0
(12175 3875);
PAINT WHITE (12175 3875);
DISPLAY INVISIBLE (12175 3875);
FORCEPROP 2 LAST CDS_LIB mstr_discrete
J 0
(12175 3875);
PAINT MONO (12175 3875);
DISPLAY INVISIBLE (12175 3875);
FORCEPROP 2 LAST ROOM P3V3_STBY_VR
J 0
(12175 3875);
PAINT GREEN (12175 3875);
DISPLAY INVISIBLE (12175 3875);
FORCEADD CAP..1
(9750 3900);
FORCEPROP 1 LASTPIN (9750 3800) $PN 2
J 0
(9760 3780);
DISPLAY 0.617021 (9760 3780);
PAINT WHITE (9760 3780);
FORCEPROP 1 LASTPIN (9750 4000) $PN 1
J 0
(9760 3980);
DISPLAY 0.617021 (9760 3980);
PAINT WHITE (9760 3980);
FORCEPROP 1 LAST VOLTAGE 50V
J 0
(9900 3800);
DISPLAY 0.617021 (9900 3800);
PAINT SKYBLUE (9900 3800);
FORCEPROP 1 LAST MATERIAL EMPTY
J 0
(10050 3850);
DISPLAY 0.617021 (10050 3850);
PAINT RED (10050 3850);
FORCEPROP 1 LAST PART_NUMBER A36096-091
J 0
(10050 3900);
DISPLAY 0.617021 (10050 3900);
PAINT BLUE (10050 3900);
FORCEPROP 1 LAST PACK_TYPE 0402LF
J 0
(10050 3950);
DISPLAY 0.617021 (10050 3950);
PAINT SKYBLUE (10050 3950);
FORCEPROP 1 LAST TOLERANCE 10%
J 0
(9900 3850);
DISPLAY 0.617021 (9900 3850);
PAINT SKYBLUE (9900 3850);
FORCEPROP 1 LAST VALUE 3300PF
J 0
(9900 3900);
DISPLAY 0.617021 (9900 3900);
PAINT SKYBLUE (9900 3900);
FORCEPROP 1 LAST LOCATION C8F3
J 0
(9900 3950);
DISPLAY 0.617021 (9900 3950);
PAINT AQUA (9900 3950);
FORCEPROP 2 LAST REUSE_ID 26
J 0
(9800 4100);
DISPLAY 1.042553 (9800 4100);
PAINT ORANGE (9800 4100);
DISPLAY INVISIBLE (9800 4100);
FORCEPROP 2 LAST CDS_SEC 1
J 0
(9800 4100);
DISPLAY 1.042553 (9800 4100);
PAINT ORANGE (9800 4100);
DISPLAY INVISIBLE (9800 4100);
FORCEPROP 2 LAST $SEC 1
J 0
(9800 4100);
DISPLAY 0.680851 (9800 4100);
PAINT MONO (9800 4100);
DISPLAY INVISIBLE (9800 4100);
FORCEPROP 2 LAST BOM_COST P3V3_STBY_VR
J 0
(9800 4050);
DISPLAY 1.042553 (9800 4050);
PAINT WHITE (9800 4050);
DISPLAY INVISIBLE (9800 4050);
FORCEPROP 2 LAST CDS_LOCATION C8F3
J 0
(9850 4000);
DISPLAY 0.617021 (9850 4000);
PAINT AQUA (9850 4000);
DISPLAY INVISIBLE (9850 4000);
FORCEPROP 1 LAST PATH I163
J 0
(9800 4050);
DISPLAY 0.978723 (9800 4050);
PAINT WHITE (9800 4050);
DISPLAY INVISIBLE (9800 4050);
FORCEPROP 2 LAST ROOM P3V3_STBY_VR
J 0
(9800 4025);
PAINT GREEN (9800 4025);
DISPLAY INVISIBLE (9800 4025);
FORCEPROP 2 LAST CDS_LIB mstr_discrete
J 0
(9750 3900);
PAINT MONO (9750 3900);
DISPLAY INVISIBLE (9750 3900);
FORCEADD AGND_SCSI..1
(6975 2100);
FORCEPROP 3 LASTPIN (6975 2150) SIG_NAME AGND_P3V3_STBY\g
J 0
(6985 2160);
DISPLAY 0.659574 (6985 2160);
PAINT MONO (6985 2160);
DISPLAY INVISIBLE (6985 2160);
FORCEPROP 1 LAST HDL_POWER AGND_P3V3_STBY
J 1
(7000 2025);
DISPLAY 0.617021 (7000 2025);
PAINT GREEN (7000 2025);
FORCEPROP 1 LAST VOLTAGE 0V
J 0
(6825 2125);
DISPLAY 1.021277 (6825 2125);
PAINT SKYBLUE (6825 2125);
DISPLAY INVISIBLE (6825 2125);
FORCEPROP 1 LAST PATH I164
J 0
(7050 2100);
DISPLAY 0.872340 (7050 2100);
PAINT AQUA (7050 2100);
DISPLAY INVISIBLE (7050 2100);
FORCEPROP 2 LAST CDS_LIB mstr_symbols
J 0
(6975 2100);
PAINT MONO (6975 2100);
DISPLAY INVISIBLE (6975 2100);
FORCEPROP 1 LAST BODY_TYPE PLUMBING
J 0
(6930 2057);
DISPLAY 0.340426 (6930 2057);
PAINT GREEN (6930 2057);
DISPLAY INVISIBLE (6930 2057);
FORCEADD AGND_SCSI..1
(6450 1550);
FORCEPROP 3 LASTPIN (6450 1600) SIG_NAME AGND_P3V3_STBY\g
J 0
(6460 1610);
DISPLAY 0.659574 (6460 1610);
PAINT MONO (6460 1610);
DISPLAY INVISIBLE (6460 1610);
FORCEPROP 1 LAST HDL_POWER AGND_P3V3_STBY
J 1
(6475 1475);
DISPLAY 0.617021 (6475 1475);
PAINT GREEN (6475 1475);
FORCEPROP 2 LAST CDS_LIB mstr_symbols
J 0
(6450 1550);
PAINT MONO (6450 1550);
DISPLAY INVISIBLE (6450 1550);
FORCEPROP 1 LAST PATH I165
J 0
(6525 1550);
DISPLAY 0.872340 (6525 1550);
PAINT AQUA (6525 1550);
DISPLAY INVISIBLE (6525 1550);
FORCEPROP 1 LAST VOLTAGE 0V
J 0
(6300 1575);
DISPLAY 1.021277 (6300 1575);
PAINT SKYBLUE (6300 1575);
DISPLAY INVISIBLE (6300 1575);
FORCEPROP 1 LAST BODY_TYPE PLUMBING
J 0
(6405 1507);
DISPLAY 0.340426 (6405 1507);
PAINT GREEN (6405 1507);
DISPLAY INVISIBLE (6405 1507);
FORCEADD AGND_SCSI..1
(6175 2175);
FORCEPROP 3 LASTPIN (6175 2225) SIG_NAME AGND_P3V3_STBY\g
J 0
(6185 2235);
DISPLAY 0.659574 (6185 2235);
PAINT MONO (6185 2235);
DISPLAY INVISIBLE (6185 2235);
FORCEPROP 1 LAST HDL_POWER AGND_P3V3_STBY
J 1
(6200 2100);
DISPLAY 0.617021 (6200 2100);
PAINT GREEN (6200 2100);
FORCEPROP 1 LAST VOLTAGE 0V
J 0
(6025 2200);
DISPLAY 1.021277 (6025 2200);
PAINT SKYBLUE (6025 2200);
DISPLAY INVISIBLE (6025 2200);
FORCEPROP 1 LAST PATH I166
J 0
(6250 2175);
DISPLAY 0.872340 (6250 2175);
PAINT AQUA (6250 2175);
DISPLAY INVISIBLE (6250 2175);
FORCEPROP 2 LAST CDS_LIB mstr_symbols
J 0
(6175 2175);
PAINT MONO (6175 2175);
DISPLAY INVISIBLE (6175 2175);
FORCEPROP 1 LAST BODY_TYPE PLUMBING
J 0
(6130 2132);
DISPLAY 0.340426 (6130 2132);
PAINT GREEN (6130 2132);
DISPLAY INVISIBLE (6130 2132);
FORCEADD AGND_SCSI..1
(5500 3100);
FORCEPROP 3 LASTPIN (5500 3150) SIG_NAME AGND_P3V3_STBY\g
J 0
(5510 3160);
DISPLAY 0.659574 (5510 3160);
PAINT MONO (5510 3160);
DISPLAY INVISIBLE (5510 3160);
FORCEPROP 1 LAST HDL_POWER AGND_P3V3_STBY
J 1
(5525 3025);
DISPLAY 0.617021 (5525 3025);
PAINT GREEN (5525 3025);
FORCEPROP 1 LAST PATH I167
J 0
(5575 3100);
DISPLAY 0.872340 (5575 3100);
PAINT AQUA (5575 3100);
DISPLAY INVISIBLE (5575 3100);
FORCEPROP 2 LAST CDS_LIB mstr_symbols
J 0
(5500 3100);
PAINT MONO (5500 3100);
DISPLAY INVISIBLE (5500 3100);
FORCEPROP 1 LAST VOLTAGE 0V
J 0
(5350 3125);
DISPLAY 1.021277 (5350 3125);
PAINT SKYBLUE (5350 3125);
DISPLAY INVISIBLE (5350 3125);
FORCEPROP 1 LAST BODY_TYPE PLUMBING
J 0
(5455 3057);
DISPLAY 0.340426 (5455 3057);
PAINT GREEN (5455 3057);
DISPLAY INVISIBLE (5455 3057);
FORCEADD AGND_SCSI..1
(9475 800);
FORCEPROP 3 LASTPIN (9475 850) SIG_NAME AGND_P3V3_STBY\g
J 0
(9485 860);
DISPLAY 0.659574 (9485 860);
PAINT MONO (9485 860);
DISPLAY INVISIBLE (9485 860);
FORCEPROP 1 LAST HDL_POWER AGND_P3V3_STBY
J 1
(9500 725);
DISPLAY 0.617021 (9500 725);
PAINT GREEN (9500 725);
FORCEPROP 1 LAST VOLTAGE 0V
J 0
(9325 825);
DISPLAY 1.021277 (9325 825);
PAINT SKYBLUE (9325 825);
DISPLAY INVISIBLE (9325 825);
FORCEPROP 2 LAST CDS_LIB mstr_symbols
J 0
(9475 800);
PAINT MONO (9475 800);
DISPLAY INVISIBLE (9475 800);
FORCEPROP 1 LAST PATH I168
J 0
(9550 800);
DISPLAY 0.872340 (9550 800);
PAINT AQUA (9550 800);
DISPLAY INVISIBLE (9550 800);
FORCEPROP 1 LAST BODY_TYPE PLUMBING
J 0
(9430 757);
DISPLAY 0.340426 (9430 757);
PAINT GREEN (9430 757);
DISPLAY INVISIBLE (9430 757);
FORCEADD AGND_SCSI..1
(10725 1625);
FORCEPROP 3 LASTPIN (10725 1675) SIG_NAME AGND_P3V3_STBY\g
J 0
(10735 1685);
DISPLAY 0.659574 (10735 1685);
PAINT MONO (10735 1685);
DISPLAY INVISIBLE (10735 1685);
FORCEPROP 1 LAST HDL_POWER AGND_P3V3_STBY
J 1
(10750 1550);
DISPLAY 0.617021 (10750 1550);
PAINT GREEN (10750 1550);
FORCEPROP 1 LAST VOLTAGE 0V
J 0
(10575 1650);
DISPLAY 1.021277 (10575 1650);
PAINT SKYBLUE (10575 1650);
DISPLAY INVISIBLE (10575 1650);
FORCEPROP 2 LAST CDS_LIB mstr_symbols
J 0
(10725 1625);
PAINT MONO (10725 1625);
DISPLAY INVISIBLE (10725 1625);
FORCEPROP 1 LAST PATH I169
J 0
(10800 1625);
DISPLAY 0.872340 (10800 1625);
PAINT AQUA (10800 1625);
DISPLAY INVISIBLE (10800 1625);
FORCEPROP 1 LAST BODY_TYPE PLUMBING
J 0
(10680 1582);
DISPLAY 0.340426 (10680 1582);
PAINT GREEN (10680 1582);
DISPLAY INVISIBLE (10680 1582);
FORCEADD CSD87384M..1
(9250 3400);
FORCEPROP 1 LAST PART_NUMBER H66258-001
J 0
(9000 3100);
DISPLAY 0.617021 (9000 3100);
PAINT BLUE (9000 3100);
FORCEPROP 2 LASTPIN (9550 3350) $PN 5
J 0
(9560 3360);
DISPLAY 0.617021 (9560 3360);
PAINT ORANGE (9560 3360);
FORCEPROP 2 LASTPIN (9550 3250) $PN 3
J 0
(9560 3260);
DISPLAY 0.617021 (9560 3260);
PAINT ORANGE (9560 3260);
FORCEPROP 1 LAST LOCATION EU8E1
J 0
(9000 3750);
DISPLAY 0.617021 (9000 3750);
PAINT AQUA (9000 3750);
FORCEPROP 1 LAST MATERIAL IC
J 0
(9000 3700);
DISPLAY 0.617021 (9000 3700);
PAINT SKYBLUE (9000 3700);
FORCEPROP 2 LASTPIN (8950 3500) $PN 2
J 2
(8940 3510);
DISPLAY 0.617021 (8940 3510);
PAINT ORANGE (8940 3510);
FORCEPROP 2 LASTPIN (8950 3400) $PN 1
J 2
(8940 3410);
DISPLAY 0.617021 (8940 3410);
PAINT ORANGE (8940 3410);
FORCEPROP 2 LASTPIN (8950 3300) $PN 4
J 2
(8940 3310);
DISPLAY 0.617021 (8940 3310);
PAINT ORANGE (8940 3310);
FORCEPROP 0 LAST ROOM P3V3_STBY_VR
J 0
(9000 3850);
DISPLAY 1.021277 (9000 3850);
PAINT ORANGE (9000 3850);
DISPLAY INVISIBLE (9000 3850);
FORCEPROP 1 LAST PATH I170
J 0
(9300 3700);
PAINT GREEN (9300 3700);
DISPLAY INVISIBLE (9300 3700);
FORCEPROP 2 LAST CDS_LOCATION EU8E1
J 0
(9000 3750);
DISPLAY 0.617021 (9000 3750);
PAINT AQUA (9000 3750);
DISPLAY INVISIBLE (9000 3750);
FORCEPROP 2 LAST SEC 1
J 0
(9000 3800);
DISPLAY 0.680851 (9000 3800);
PAINT MONO (9000 3800);
DISPLAY INVISIBLE (9000 3800);
FORCEPROP 2 LAST SEC_TYPE SM
J 0
(9000 3800);
DISPLAY 1.021277 (9000 3800);
PAINT ORANGE (9000 3800);
DISPLAY INVISIBLE (9000 3800);
FORCEPROP 1 LAST PACK_TYPE SM
J 0
(9000 3800);
PAINT SKYBLUE (9000 3800);
DISPLAY INVISIBLE (9000 3800);
FORCEPROP 2 LAST CDS_LIB mstr_discrete
J 0
(9250 3400);
PAINT MONO (9250 3400);
DISPLAY INVISIBLE (9250 3400);
FORCEADD RES..1
(7175 3825);
FORCEPROP 1 LASTPIN (7075 3825) $PN 1
J 0
(7087 3837);
DISPLAY 0.617021 (7087 3837);
PAINT ORANGE (7087 3837);
FORCEPROP 1 LAST WATTAGE 1/16W
J 2
(7150 3675);
DISPLAY 0.617021 (7150 3675);
PAINT SKYBLUE (7150 3675);
FORCEPROP 1 LAST VALUE 22.1
J 2
(7150 3725);
DISPLAY 0.617021 (7150 3725);
PAINT SKYBLUE (7150 3725);
FORCEPROP 1 LAST PART_NUMBER G21796-250
J 0
(7125 3925);
DISPLAY 0.617021 (7125 3925);
PAINT BLUE (7125 3925);
FORCEPROP 1 LAST LOCATION R8F10
J 0
(7125 3875);
DISPLAY 0.617021 (7125 3875);
PAINT AQUA (7125 3875);
FORCEPROP 1 LAST MATERIAL CHIP
J 0
(7175 3675);
DISPLAY 0.617021 (7175 3675);
PAINT SKYBLUE (7175 3675);
FORCEPROP 1 LASTPIN (7275 3825) $PN 2
J 0
(7237 3837);
DISPLAY 0.617021 (7237 3837);
PAINT ORANGE (7237 3837);
FORCEPROP 1 LAST PACK_TYPE 0402
J 0
(7325 3725);
DISPLAY 0.617021 (7325 3725);
PAINT SKYBLUE (7325 3725);
FORCEPROP 1 LAST TOLERANCE 1.0%
J 0
(7175 3725);
DISPLAY 0.617021 (7175 3725);
PAINT SKYBLUE (7175 3725);
FORCEPROP 0 LAST ROOM P3V3_STBY_VR
J 0
(7125 4025);
DISPLAY 1.021277 (7125 4025);
PAINT ORANGE (7125 4025);
DISPLAY INVISIBLE (7125 4025);
FORCEPROP 1 LAST PATH I171
J 0
(7125 3975);
DISPLAY 0.978723 (7125 3975);
PAINT WHITE (7125 3975);
DISPLAY INVISIBLE (7125 3975);
FORCEPROP 2 LAST CDS_LOCATION R8F10
J 0
(7125 3875);
DISPLAY 0.617021 (7125 3875);
PAINT AQUA (7125 3875);
DISPLAY INVISIBLE (7125 3875);
FORCEPROP 2 LAST SEC 1
J 0
(7125 4025);
DISPLAY 0.680851 (7125 4025);
PAINT MONO (7125 4025);
DISPLAY INVISIBLE (7125 4025);
FORCEPROP 2 LAST SEC_TYPE 0402
J 0
(7125 4025);
DISPLAY 1.021277 (7125 4025);
PAINT ORANGE (7125 4025);
DISPLAY INVISIBLE (7125 4025);
FORCEPROP 2 LAST CDS_LIB mstr_discrete
J 0
(7175 3825);
PAINT MONO (7175 3825);
DISPLAY INVISIBLE (7175 3825);
FORCEADD CAP..1
(12425 3875);
FORCEPROP 1 LAST MATERIAL X6S
J 0
(12475 3775);
DISPLAY 0.617021 (12475 3775);
PAINT SKYBLUE (12475 3775);
FORCEPROP 1 LAST TOLERANCE 20%
J 0
(12475 3825);
DISPLAY 0.617021 (12475 3825);
PAINT SKYBLUE (12475 3825);
FORCEPROP 1 LASTPIN (12425 3775) $PN 2
J 0
(12435 3755);
DISPLAY 0.787234 (12435 3755);
PAINT ORANGE (12435 3755);
FORCEPROP 1 LAST VALUE 22UF
J 0
(12475 3925);
DISPLAY 0.617021 (12475 3925);
PAINT SKYBLUE (12475 3925);
FORCEPROP 1 LAST PART_NUMBER C95333-008
J 0
(12475 3725);
DISPLAY 0.617021 (12475 3725);
PAINT BLUE (12475 3725);
FORCEPROP 1 LAST VOLTAGE 6.3V
J 0
(12475 3875);
DISPLAY 0.617021 (12475 3875);
PAINT SKYBLUE (12475 3875);
FORCEPROP 1 LASTPIN (12425 3975) $PN 1
J 0
(12435 3955);
DISPLAY 0.787234 (12435 3955);
PAINT ORANGE (12435 3955);
FORCEPROP 1 LAST PACK_TYPE 0805
J 0
(12475 3675);
DISPLAY 0.617021 (12475 3675);
PAINT SKYBLUE (12475 3675);
FORCEPROP 1 LAST LOCATION C2T9
J 0
(12475 3975);
DISPLAY 0.617021 (12475 3975);
PAINT AQUA (12475 3975);
FORCEPROP 2 LAST SEC_TYPE 0805
J 0
(12475 4075);
DISPLAY 1.021277 (12475 4075);
PAINT ORANGE (12475 4075);
DISPLAY INVISIBLE (12475 4075);
FORCEPROP 2 LAST SEC 1
J 0
(12475 4075);
PAINT MONO (12475 4075);
DISPLAY INVISIBLE (12475 4075);
FORCEPROP 1 LAST PATH I174
J 0
(12475 4025);
DISPLAY 0.978723 (12475 4025);
PAINT WHITE (12475 4025);
DISPLAY INVISIBLE (12475 4025);
FORCEPROP 2 LAST REUSE_ID 33
J 0
(12475 4075);
DISPLAY 1.042553 (12475 4075);
PAINT ORANGE (12475 4075);
DISPLAY INVISIBLE (12475 4075);
FORCEPROP 2 LAST CDS_LOCATION C2T9
J 0
(12475 3975);
DISPLAY 0.617021 (12475 3975);
PAINT AQUA (12475 3975);
DISPLAY INVISIBLE (12475 3975);
FORCEPROP 2 LAST BOM_COST P3V3_STBY_VR
J 0
(12425 3875);
PAINT WHITE (12425 3875);
DISPLAY INVISIBLE (12425 3875);
FORCEPROP 2 LAST CDS_LIB mstr_discrete
J 0
(12425 3875);
PAINT MONO (12425 3875);
DISPLAY INVISIBLE (12425 3875);
FORCEPROP 2 LAST ROOM P3V3_STBY_VR
J 0
(12425 3875);
PAINT GREEN (12425 3875);
DISPLAY INVISIBLE (12425 3875);
FORCEADD GND..1
(12425 3575);
FORCEPROP 3 LASTPIN (12425 3625) SIG_NAME GND\g
J 0
(12435 3635);
DISPLAY 0.659574 (12435 3635);
PAINT MONO (12435 3635);
DISPLAY INVISIBLE (12435 3635);
FORCEPROP 2 LAST BOM_COST PVPP_KLM_VR
J 0
(11575 3650);
DISPLAY 1.042553 (11575 3650);
PAINT WHITE (11575 3650);
DISPLAY INVISIBLE (11575 3650);
FORCEPROP 2 LAST ROOM PVPP_KLM_VR
J 0
(11850 3650);
DISPLAY 1.042553 (11850 3650);
PAINT GREEN (11850 3650);
DISPLAY INVISIBLE (11850 3650);
FORCEPROP 1 LAST SIZE 1B
J 0
(12500 3525);
DISPLAY 0.872340 (12500 3525);
PAINT GREEN (12500 3525);
DISPLAY INVISIBLE (12500 3525);
FORCEPROP 1 LAST PATH I175
J 0
(12500 3575);
DISPLAY 0.872340 (12500 3575);
PAINT AQUA (12500 3575);
DISPLAY INVISIBLE (12500 3575);
FORCEPROP 2 LAST CDS_LIB mstr_symbols
J 0
(12425 3575);
PAINT MONO (12425 3575);
DISPLAY INVISIBLE (12425 3575);
FORCEPROP 1 LAST VOLTAGE 0
J 0
(12425 3575);
PAINT SKYBLUE (12425 3575);
DISPLAY INVISIBLE (12425 3575);
FORCEPROP 1 LAST BODY_TYPE PLUMBING
J 0
(12380 3532);
DISPLAY 0.340426 (12380 3532);
PAINT GREEN (12380 3532);
DISPLAY INVISIBLE (12380 3532);
FORCEPROP 1 LAST HDL_POWER GND
J 0
(12425 3725);
DISPLAY 0.872340 (12425 3725);
PAINT GREEN (12425 3725);
DISPLAY INVISIBLE (12425 3725);
FORCEADD RES..1
(6400 2725);
FORCEPROP 1 LAST TOLERANCE 5%
J 0
(6350 2625);
DISPLAY 0.617021 (6350 2625);
PAINT SKYBLUE (6350 2625);
FORCEPROP 1 LAST WATTAGE 1/16W
J 2
(6375 2575);
DISPLAY 0.617021 (6375 2575);
PAINT SKYBLUE (6375 2575);
FORCEPROP 1 LAST LOCATION R8F2
J 0
(6350 2775);
DISPLAY 0.617021 (6350 2775);
PAINT AQUA (6350 2775);
FORCEPROP 1 LAST MATERIAL CHIP
J 0
(6400 2575);
DISPLAY 0.617021 (6400 2575);
PAINT SKYBLUE (6400 2575);
FORCEPROP 1 LAST VALUE 0.0
J 2
(6300 2625);
DISPLAY 0.617021 (6300 2625);
PAINT SKYBLUE (6300 2625);
FORCEPROP 1 LASTPIN (6300 2725) $PN 1
J 0
(6312 2737);
DISPLAY 0.787234 (6312 2737);
PAINT ORANGE (6312 2737);
FORCEPROP 1 LAST PACK_TYPE 0402
J 0
(6475 2625);
DISPLAY 0.617021 (6475 2625);
PAINT SKYBLUE (6475 2625);
FORCEPROP 1 LASTPIN (6500 2725) $PN 2
J 0
(6462 2737);
DISPLAY 0.787234 (6462 2737);
PAINT ORANGE (6462 2737);
FORCEPROP 1 LAST PART_NUMBER G21497-005
J 0
(6250 2675);
DISPLAY 0.617021 (6250 2675);
PAINT BLUE (6250 2675);
FORCEPROP 2 LAST ROOM PVCCIN_CPU0_VR
J 0
(6350 2825);
DISPLAY 1.361702 (6350 2825);
PAINT ORANGE (6350 2825);
DISPLAY INVISIBLE (6350 2825);
FORCEPROP 1 LAST PATH I176
J 0
(6350 2875);
DISPLAY 0.978723 (6350 2875);
PAINT WHITE (6350 2875);
DISPLAY INVISIBLE (6350 2875);
FORCEPROP 2 LAST CDS_LIB mstr_discrete
J 0
(6400 2725);
PAINT ORANGE (6400 2725);
DISPLAY INVISIBLE (6400 2725);
FORCEPROP 2 LAST CDS_LOCATION R8F2
J 0
(6350 2775);
DISPLAY 0.617021 (6350 2775);
PAINT AQUA (6350 2775);
DISPLAY INVISIBLE (6350 2775);
FORCEPROP 2 LAST SEC_TYPE 0402
J 0
(6350 2925);
DISPLAY 1.021277 (6350 2925);
PAINT ORANGE (6350 2925);
DISPLAY INVISIBLE (6350 2925);
FORCEPROP 2 LAST SEC 1
J 0
(6350 2925);
PAINT MONO (6350 2925);
DISPLAY INVISIBLE (6350 2925);
FORCEADD RES..2
(6950 3250);
FORCEPROP 1 LAST LOCATION R8E40
J 0
(6995 3375);
DISPLAY 0.617021 (6995 3375);
PAINT AQUA (6995 3375);
FORCEPROP 1 LAST PART_NUMBER G21796-010
J 0
(6990 3125);
DISPLAY 0.617021 (6990 3125);
PAINT BLUE (6990 3125);
FORCEPROP 1 LAST MATERIAL EMPTY
J 0
(6990 3175);
DISPLAY 0.617021 (6990 3175);
PAINT RED (6990 3175);
FORCEPROP 1 LAST WATTAGE 1/16W
J 0
(6990 3225);
DISPLAY 0.617021 (6990 3225);
PAINT SKYBLUE (6990 3225);
FORCEPROP 1 LAST VALUE 100.0K
J 0
(6995 3325);
DISPLAY 0.617021 (6995 3325);
PAINT SKYBLUE (6995 3325);
FORCEPROP 1 LAST TOLERANCE 1%
J 0
(6995 3275);
DISPLAY 0.617021 (6995 3275);
PAINT SKYBLUE (6995 3275);
FORCEPROP 1 LAST PACK_TYPE 0402
J 0
(6990 3075);
DISPLAY 0.617021 (6990 3075);
PAINT SKYBLUE (6990 3075);
FORCEPROP 1 LASTPIN (6950 3350) $PN 1
J 0
(6955 3312);
DISPLAY 0.787234 (6955 3312);
PAINT ORANGE (6955 3312);
FORCEPROP 1 LASTPIN (6950 3150) $PN 2
J 0
(6955 3160);
DISPLAY 0.787234 (6955 3160);
PAINT ORANGE (6955 3160);
FORCEPROP 2 LAST CDS_LIB mstr_discrete
J 0
(6950 3250);
PAINT ORANGE (6950 3250);
DISPLAY INVISIBLE (6950 3250);
FORCEPROP 2 LAST CDS_LOCATION R8E40
J 0
(6995 3375);
DISPLAY 0.617021 (6995 3375);
PAINT AQUA (6995 3375);
DISPLAY INVISIBLE (6995 3375);
FORCEPROP 1 LAST PATH I177
J 0
(7000 3425);
DISPLAY 0.978723 (7000 3425);
PAINT WHITE (7000 3425);
DISPLAY INVISIBLE (7000 3425);
FORCEPROP 0 LAST ROOM BMC
J 0
(7000 3475);
DISPLAY 0.617021 (7000 3475);
PAINT ORANGE (7000 3475);
DISPLAY INVISIBLE (7000 3475);
FORCEPROP 0 LAST BOM_COST SM_CONTROLLER
J 0
(7000 3575);
DISPLAY 1.021277 (7000 3575);
PAINT ORANGE (7000 3575);
DISPLAY INVISIBLE (7000 3575);
FORCEPROP 2 LAST SEC 1
J 0
(7000 3475);
PAINT MONO (7000 3475);
DISPLAY INVISIBLE (7000 3475);
FORCEPROP 2 LAST SEC_TYPE 0402
J 0
(7000 3475);
DISPLAY 1.021277 (7000 3475);
PAINT ORANGE (7000 3475);
DISPLAY INVISIBLE (7000 3475);
FORCEADD P3V3_STBY..1
(6950 3500);
FORCEPROP 3 LASTPIN (6950 3450) SIG_NAME P3V3_STBY\g
J 0
(6960 3460);
DISPLAY 0.659574 (6960 3460);
PAINT MONO (6960 3460);
DISPLAY INVISIBLE (6960 3460);
FORCEPROP 1 LAST PATH I178
J 0
(6995 3502);
DISPLAY 0.340426 (6995 3502);
PAINT GREEN (6995 3502);
DISPLAY INVISIBLE (6995 3502);
FORCEPROP 2 LAST CDS_LIB mstr_symbols
J 0
(6950 3500);
PAINT ORANGE (6950 3500);
DISPLAY INVISIBLE (6950 3500);
FORCEPROP 1 LAST SIZE 1B
J 0
(6995 3522);
DISPLAY 0.340426 (6995 3522);
PAINT GREEN (6995 3522);
DISPLAY INVISIBLE (6995 3522);
FORCEPROP 1 LAST VOLTAGE +3.3V
J 0
(7150 3650);
DISPLAY 1.021277 (7150 3650);
PAINT SKYBLUE (7150 3650);
DISPLAY INVISIBLE (7150 3650);
FORCEPROP 1 LAST BODY_TYPE PLUMBING
J 0
(6905 3457);
DISPLAY 0.340426 (6905 3457);
PAINT GREEN (6905 3457);
DISPLAY INVISIBLE (6905 3457);
FORCEPROP 1 LAST HDL_POWER P3V3_STBY
J 0
(6650 3375);
DISPLAY 0.872340 (6650 3375);
PAINT ORANGE (6650 3375);
DISPLAY INVISIBLE (6650 3375);
FORCEADD GND..1
(6700 4025);
FORCEPROP 3 LASTPIN (6700 4075) SIG_NAME GND\g
J 0
(6710 4085);
DISPLAY 0.659574 (6710 4085);
PAINT MONO (6710 4085);
DISPLAY INVISIBLE (6710 4085);
FORCEPROP 2 LAST CDS_LIB mstr_symbols
J 0
(6700 4025);
PAINT MONO (6700 4025);
DISPLAY INVISIBLE (6700 4025);
FORCEPROP 2 LAST BOM_COST PVPP_KLM_VR
J 0
(5850 4100);
DISPLAY 1.042553 (5850 4100);
PAINT WHITE (5850 4100);
DISPLAY INVISIBLE (5850 4100);
FORCEPROP 2 LAST ROOM PVPP_KLM_VR
J 0
(6125 4100);
DISPLAY 1.042553 (6125 4100);
PAINT GREEN (6125 4100);
DISPLAY INVISIBLE (6125 4100);
FORCEPROP 1 LAST VOLTAGE 0
J 0
(6700 4025);
PAINT SKYBLUE (6700 4025);
DISPLAY INVISIBLE (6700 4025);
FORCEPROP 1 LAST SIZE 1B
J 0
(6775 3975);
DISPLAY 0.872340 (6775 3975);
PAINT GREEN (6775 3975);
DISPLAY INVISIBLE (6775 3975);
FORCEPROP 1 LAST PATH I179
J 0
(6775 4025);
DISPLAY 0.872340 (6775 4025);
PAINT AQUA (6775 4025);
DISPLAY INVISIBLE (6775 4025);
FORCEPROP 1 LAST BODY_TYPE PLUMBING
J 0
(6655 3982);
DISPLAY 0.340426 (6655 3982);
PAINT GREEN (6655 3982);
DISPLAY INVISIBLE (6655 3982);
FORCEPROP 1 LAST HDL_POWER GND
J 0
(6700 4175);
DISPLAY 0.872340 (6700 4175);
PAINT GREEN (6700 4175);
DISPLAY INVISIBLE (6700 4175);
FORCEADD GND..1
(7450 4025);
FORCEPROP 3 LASTPIN (7450 4075) SIG_NAME GND\g
J 0
(7460 4085);
DISPLAY 0.659574 (7460 4085);
PAINT MONO (7460 4085);
DISPLAY INVISIBLE (7460 4085);
FORCEPROP 1 LAST SIZE 1B
J 0
(7525 3975);
DISPLAY 0.872340 (7525 3975);
PAINT GREEN (7525 3975);
DISPLAY INVISIBLE (7525 3975);
FORCEPROP 1 LAST VOLTAGE 0
J 0
(7450 4025);
PAINT SKYBLUE (7450 4025);
DISPLAY INVISIBLE (7450 4025);
FORCEPROP 2 LAST ROOM PVPP_KLM_VR
J 0
(6875 4100);
DISPLAY 1.042553 (6875 4100);
PAINT GREEN (6875 4100);
DISPLAY INVISIBLE (6875 4100);
FORCEPROP 2 LAST BOM_COST PVPP_KLM_VR
J 0
(6600 4100);
DISPLAY 1.042553 (6600 4100);
PAINT WHITE (6600 4100);
DISPLAY INVISIBLE (6600 4100);
FORCEPROP 2 LAST CDS_LIB mstr_symbols
J 0
(7450 4025);
PAINT MONO (7450 4025);
DISPLAY INVISIBLE (7450 4025);
FORCEPROP 1 LAST PATH I180
J 0
(7525 4025);
DISPLAY 0.872340 (7525 4025);
PAINT AQUA (7525 4025);
DISPLAY INVISIBLE (7525 4025);
FORCEPROP 1 LAST BODY_TYPE PLUMBING
J 0
(7405 3982);
DISPLAY 0.340426 (7405 3982);
PAINT GREEN (7405 3982);
DISPLAY INVISIBLE (7405 3982);
FORCEPROP 1 LAST HDL_POWER GND
J 0
(7450 4175);
DISPLAY 0.872340 (7450 4175);
PAINT GREEN (7450 4175);
DISPLAY INVISIBLE (7450 4175);
FORCEADD SC22U16V5MX-4-GP..1
(6700 4275);
FORCEPROP 1 LAST LOCATION C9F1
J 0
(6800 4410);
DISPLAY 0.617021 (6800 4410);
PAINT GREEN (6800 4410);
FORCEPROP 1 LAST VALUE SC22U16V5MX-4-GP
R 1
J 0
(6775 4045);
DISPLAY 0.617021 (6775 4045);
PAINT GREEN (6775 4045);
FORCEPROP 2 LAST TOLERANCE 20%
J 0
(6800 4300);
DISPLAY 0.638298 (6800 4300);
PAINT GREEN (6800 4300);
FORCEPROP 2 LAST ATTRIBUTE 22UF
J 0
(6800 4350);
DISPLAY 0.638298 (6800 4350);
PAINT GREEN (6800 4350);
FORCEPROP 2 LASTPIN (6700 4350) $PN 1
R 1
J 0
(6690 4360);
DISPLAY 0.808511 (6690 4360);
PAINT ORANGE (6690 4360);
FORCEPROP 2 LAST TYPE X6S
J 0
(6800 4200);
DISPLAY 0.638298 (6800 4200);
PAINT GREEN (6800 4200);
FORCEPROP 2 LAST PACK_SIZE 0805
J 0
(6800 4150);
DISPLAY 0.638298 (6800 4150);
PAINT GREEN (6800 4150);
FORCEPROP 2 LAST RATED 16V
J 0
(6800 4250);
DISPLAY 0.638298 (6800 4250);
PAINT GREEN (6800 4250);
FORCEPROP 2 LASTPIN (6700 4200) $PN 2
R 1
J 2
(6690 4190);
DISPLAY 0.808511 (6690 4190);
PAINT ORANGE (6690 4190);
FORCEPROP 1 LAST PACK_TYPE SMD-BCG5
J 0
(6700 4275);
DISPLAY 0.617021 (6700 4275);
PAINT GREEN (6700 4275);
DISPLAY INVISIBLE (6700 4275);
FORCEPROP 2 LAST SEC 1
J 0
(6725 4350);
DISPLAY 0.680851 (6725 4350);
PAINT MONO (6725 4350);
DISPLAY INVISIBLE (6725 4350);
FORCEPROP 2 LAST SEC_TYPE SMD-BCG5
J 0
(6725 4350);
DISPLAY 1.021277 (6725 4350);
PAINT ORANGE (6725 4350);
DISPLAY INVISIBLE (6725 4350);
FORCEPROP 1 LAST PART_NUMBER 078.22611.0811
J 0
(6700 4275);
DISPLAY 0.617021 (6700 4275);
PAINT GREEN (6700 4275);
DISPLAY INVISIBLE (6700 4275);
FORCEPROP 2 LAST CDS_LIB w_hdl
J 0
(6700 4275);
PAINT MONO (6700 4275);
DISPLAY INVISIBLE (6700 4275);
FORCEPROP 1 LAST CDS_LMAN_SYM_OUTLINE -50,25,50,-25
J 0
(6700 4275);
DISPLAY 0.468085 (6700 4275);
PAINT GREEN (6700 4275);
DISPLAY INVISIBLE (6700 4275);
FORCEPROP 1 LAST PATH I181
J 0
(6700 4275);
DISPLAY 0.617021 (6700 4275);
PAINT GREEN (6700 4275);
DISPLAY INVISIBLE (6700 4275);
FORCEADD SC22U16V5MX-4-GP..1
(7000 4275);
FORCEPROP 1 LAST VALUE SC22U16V5MX-4-GP
R 1
J 0
(7075 4045);
DISPLAY 0.617021 (7075 4045);
PAINT GREEN (7075 4045);
FORCEPROP 1 LAST LOCATION C22W11
J 0
(7100 4410);
DISPLAY 0.617021 (7100 4410);
PAINT GREEN (7100 4410);
FORCEPROP 2 LASTPIN (7000 4350) $PN 1
R 1
J 0
(6990 4360);
DISPLAY 0.808511 (6990 4360);
PAINT ORANGE (6990 4360);
FORCEPROP 2 LAST TOLERANCE 20%
J 0
(7100 4300);
DISPLAY 0.638298 (7100 4300);
PAINT GREEN (7100 4300);
FORCEPROP 2 LAST RATED 16V
J 0
(7100 4250);
DISPLAY 0.638298 (7100 4250);
PAINT GREEN (7100 4250);
FORCEPROP 2 LASTPIN (7000 4200) $PN 2
R 1
J 2
(6990 4190);
DISPLAY 0.808511 (6990 4190);
PAINT ORANGE (6990 4190);
FORCEPROP 2 LAST PACK_SIZE 0805
J 0
(7100 4150);
DISPLAY 0.638298 (7100 4150);
PAINT GREEN (7100 4150);
FORCEPROP 2 LAST TYPE X6S
J 0
(7100 4200);
DISPLAY 0.638298 (7100 4200);
PAINT GREEN (7100 4200);
FORCEPROP 2 LAST ATTRIBUTE 22UF
J 0
(7100 4350);
DISPLAY 0.638298 (7100 4350);
PAINT GREEN (7100 4350);
FORCEPROP 1 LAST CDS_LMAN_SYM_OUTLINE -50,25,50,-25
J 0
(7000 4275);
DISPLAY 0.468085 (7000 4275);
PAINT GREEN (7000 4275);
DISPLAY INVISIBLE (7000 4275);
FORCEPROP 2 LAST CDS_LIB w_hdl
J 0
(7000 4275);
PAINT MONO (7000 4275);
DISPLAY INVISIBLE (7000 4275);
FORCEPROP 1 LAST PART_NUMBER 078.22611.0811
J 0
(7000 4275);
DISPLAY 0.617021 (7000 4275);
PAINT GREEN (7000 4275);
DISPLAY INVISIBLE (7000 4275);
FORCEPROP 2 LAST SEC_TYPE SMD-BCG5
J 0
(7025 4350);
DISPLAY 1.021277 (7025 4350);
PAINT ORANGE (7025 4350);
DISPLAY INVISIBLE (7025 4350);
FORCEPROP 2 LAST SEC 1
J 0
(7025 4350);
DISPLAY 0.680851 (7025 4350);
PAINT MONO (7025 4350);
DISPLAY INVISIBLE (7025 4350);
FORCEPROP 1 LAST PACK_TYPE SMD-BCG5
J 0
(7000 4275);
DISPLAY 0.617021 (7000 4275);
PAINT GREEN (7000 4275);
DISPLAY INVISIBLE (7000 4275);
FORCEPROP 1 LAST PATH I182
J 0
(7000 4275);
DISPLAY 0.617021 (7000 4275);
PAINT GREEN (7000 4275);
DISPLAY INVISIBLE (7000 4275);
FORCEADD SC22U16V5MX-4-GP..1
(7450 4275);
FORCEPROP 1 LAST VALUE SC22U16V5MX-4-GP
R 1
J 0
(7525 4045);
DISPLAY 0.617021 (7525 4045);
PAINT GREEN (7525 4045);
FORCEPROP 2 LAST RATED 16V
J 0
(7550 4250);
DISPLAY 0.638298 (7550 4250);
PAINT GREEN (7550 4250);
FORCEPROP 2 LAST PACK_SIZE 0805
J 0
(7550 4150);
DISPLAY 0.638298 (7550 4150);
PAINT GREEN (7550 4150);
FORCEPROP 2 LAST TYPE X6S
J 0
(7550 4200);
DISPLAY 0.638298 (7550 4200);
PAINT GREEN (7550 4200);
FORCEPROP 2 LAST TOLERANCE 20%
J 0
(7550 4300);
DISPLAY 0.638298 (7550 4300);
PAINT GREEN (7550 4300);
FORCEPROP 2 LAST ATTRIBUTE 22UF
J 0
(7550 4350);
DISPLAY 0.638298 (7550 4350);
PAINT GREEN (7550 4350);
FORCEPROP 1 LAST LOCATION C8E11
J 0
(7550 4410);
DISPLAY 0.617021 (7550 4410);
PAINT GREEN (7550 4410);
FORCEPROP 2 LASTPIN (7450 4350) $PN 1
R 1
J 0
(7440 4360);
DISPLAY 0.808511 (7440 4360);
PAINT ORANGE (7440 4360);
FORCEPROP 2 LASTPIN (7450 4200) $PN 2
R 1
J 2
(7440 4190);
DISPLAY 0.808511 (7440 4190);
PAINT ORANGE (7440 4190);
FORCEPROP 1 LAST CDS_LMAN_SYM_OUTLINE -50,25,50,-25
J 0
(7450 4275);
DISPLAY 0.468085 (7450 4275);
PAINT GREEN (7450 4275);
DISPLAY INVISIBLE (7450 4275);
FORCEPROP 2 LAST CDS_LIB w_hdl
J 0
(7450 4275);
PAINT MONO (7450 4275);
DISPLAY INVISIBLE (7450 4275);
FORCEPROP 1 LAST PART_NUMBER 078.22611.0811
J 0
(7450 4275);
DISPLAY 0.617021 (7450 4275);
PAINT GREEN (7450 4275);
DISPLAY INVISIBLE (7450 4275);
FORCEPROP 2 LAST SEC_TYPE SMD-BCG5
J 0
(7475 4350);
DISPLAY 1.021277 (7475 4350);
PAINT ORANGE (7475 4350);
DISPLAY INVISIBLE (7475 4350);
FORCEPROP 2 LAST SEC 1
J 0
(7475 4350);
DISPLAY 0.680851 (7475 4350);
PAINT MONO (7475 4350);
DISPLAY INVISIBLE (7475 4350);
FORCEPROP 1 LAST PACK_TYPE SMD-BCG5
J 0
(7450 4275);
DISPLAY 0.617021 (7450 4275);
PAINT GREEN (7450 4275);
DISPLAY INVISIBLE (7450 4275);
FORCEPROP 1 LAST PATH I183
J 0
(7450 4275);
DISPLAY 0.617021 (7450 4275);
PAINT GREEN (7450 4275);
DISPLAY INVISIBLE (7450 4275);
FORCEADD GND..1
(7800 4025);
FORCEPROP 3 LASTPIN (7800 4075) SIG_NAME GND\g
J 0
(7810 4085);
DISPLAY 0.659574 (7810 4085);
PAINT MONO (7810 4085);
DISPLAY INVISIBLE (7810 4085);
FORCEPROP 1 LAST PATH I184
J 0
(7875 4025);
DISPLAY 0.872340 (7875 4025);
PAINT AQUA (7875 4025);
DISPLAY INVISIBLE (7875 4025);
FORCEPROP 2 LAST CDS_LIB mstr_symbols
J 0
(7800 4025);
PAINT MONO (7800 4025);
DISPLAY INVISIBLE (7800 4025);
FORCEPROP 2 LAST BOM_COST PVPP_KLM_VR
J 0
(6950 4100);
DISPLAY 1.042553 (6950 4100);
PAINT WHITE (6950 4100);
DISPLAY INVISIBLE (6950 4100);
FORCEPROP 2 LAST ROOM PVPP_KLM_VR
J 0
(7225 4100);
DISPLAY 1.042553 (7225 4100);
PAINT GREEN (7225 4100);
DISPLAY INVISIBLE (7225 4100);
FORCEPROP 1 LAST VOLTAGE 0
J 0
(7800 4025);
PAINT SKYBLUE (7800 4025);
DISPLAY INVISIBLE (7800 4025);
FORCEPROP 1 LAST SIZE 1B
J 0
(7875 3975);
DISPLAY 0.872340 (7875 3975);
PAINT GREEN (7875 3975);
DISPLAY INVISIBLE (7875 3975);
FORCEPROP 1 LAST BODY_TYPE PLUMBING
J 0
(7755 3982);
DISPLAY 0.340426 (7755 3982);
PAINT GREEN (7755 3982);
DISPLAY INVISIBLE (7755 3982);
FORCEPROP 1 LAST HDL_POWER GND
J 0
(7800 4175);
DISPLAY 0.872340 (7800 4175);
PAINT GREEN (7800 4175);
DISPLAY INVISIBLE (7800 4175);
FORCEADD GND..1
(7000 4025);
FORCEPROP 3 LASTPIN (7000 4075) SIG_NAME GND\g
J 0
(7010 4085);
DISPLAY 0.659574 (7010 4085);
PAINT MONO (7010 4085);
DISPLAY INVISIBLE (7010 4085);
FORCEPROP 2 LAST CDS_LIB mstr_symbols
J 0
(7000 4025);
PAINT MONO (7000 4025);
DISPLAY INVISIBLE (7000 4025);
FORCEPROP 2 LAST BOM_COST PVPP_KLM_VR
J 0
(6150 4100);
DISPLAY 1.042553 (6150 4100);
PAINT WHITE (6150 4100);
DISPLAY INVISIBLE (6150 4100);
FORCEPROP 2 LAST ROOM PVPP_KLM_VR
J 0
(6425 4100);
DISPLAY 1.042553 (6425 4100);
PAINT GREEN (6425 4100);
DISPLAY INVISIBLE (6425 4100);
FORCEPROP 1 LAST VOLTAGE 0
J 0
(7000 4025);
PAINT SKYBLUE (7000 4025);
DISPLAY INVISIBLE (7000 4025);
FORCEPROP 1 LAST SIZE 1B
J 0
(7075 3975);
DISPLAY 0.872340 (7075 3975);
PAINT GREEN (7075 3975);
DISPLAY INVISIBLE (7075 3975);
FORCEPROP 1 LAST PATH I185
J 0
(7075 4025);
DISPLAY 0.872340 (7075 4025);
PAINT AQUA (7075 4025);
DISPLAY INVISIBLE (7075 4025);
FORCEPROP 1 LAST BODY_TYPE PLUMBING
J 0
(6955 3982);
DISPLAY 0.340426 (6955 3982);
PAINT GREEN (6955 3982);
DISPLAY INVISIBLE (6955 3982);
FORCEPROP 1 LAST HDL_POWER GND
J 0
(7000 4175);
DISPLAY 0.872340 (7000 4175);
PAINT GREEN (7000 4175);
DISPLAY INVISIBLE (7000 4175);
FORCEADD SC22U16V5MX-4-GP..1
(7800 4275);
FORCEPROP 1 LAST VALUE SC22U16V5MX-4-GP
R 1
J 0
(7875 4045);
DISPLAY 0.617021 (7875 4045);
PAINT GREEN (7875 4045);
FORCEPROP 2 LAST RATED 16V
J 0
(7900 4250);
DISPLAY 0.638298 (7900 4250);
PAINT GREEN (7900 4250);
FORCEPROP 2 LAST PACK_SIZE 0805
J 0
(7900 4150);
DISPLAY 0.638298 (7900 4150);
PAINT GREEN (7900 4150);
FORCEPROP 2 LAST TYPE X6S
J 0
(7900 4200);
DISPLAY 0.638298 (7900 4200);
PAINT GREEN (7900 4200);
FORCEPROP 2 LAST TOLERANCE 20%
J 0
(7900 4300);
DISPLAY 0.638298 (7900 4300);
PAINT GREEN (7900 4300);
FORCEPROP 2 LAST ATTRIBUTE 22UF
J 0
(7900 4350);
DISPLAY 0.638298 (7900 4350);
PAINT GREEN (7900 4350);
FORCEPROP 1 LAST LOCATION C22W12
J 0
(7900 4410);
DISPLAY 0.617021 (7900 4410);
PAINT GREEN (7900 4410);
FORCEPROP 2 LASTPIN (7800 4200) $PN 2
R 1
J 2
(7790 4190);
DISPLAY 0.808511 (7790 4190);
PAINT ORANGE (7790 4190);
FORCEPROP 2 LASTPIN (7800 4350) $PN 1
R 1
J 0
(7790 4360);
DISPLAY 0.808511 (7790 4360);
PAINT ORANGE (7790 4360);
FORCEPROP 1 LAST PATH I186
J 0
(7800 4275);
DISPLAY 0.617021 (7800 4275);
PAINT GREEN (7800 4275);
DISPLAY INVISIBLE (7800 4275);
FORCEPROP 1 LAST CDS_LMAN_SYM_OUTLINE -50,25,50,-25
J 0
(7800 4275);
DISPLAY 0.468085 (7800 4275);
PAINT GREEN (7800 4275);
DISPLAY INVISIBLE (7800 4275);
FORCEPROP 2 LAST CDS_LIB w_hdl
J 0
(7800 4275);
PAINT MONO (7800 4275);
DISPLAY INVISIBLE (7800 4275);
FORCEPROP 1 LAST PART_NUMBER 078.22611.0811
J 0
(7800 4275);
DISPLAY 0.617021 (7800 4275);
PAINT GREEN (7800 4275);
DISPLAY INVISIBLE (7800 4275);
FORCEPROP 2 LAST SEC_TYPE SMD-BCG5
J 0
(7825 4350);
DISPLAY 1.021277 (7825 4350);
PAINT ORANGE (7825 4350);
DISPLAY INVISIBLE (7825 4350);
FORCEPROP 2 LAST SEC 1
J 0
(7825 4350);
DISPLAY 0.680851 (7825 4350);
PAINT MONO (7825 4350);
DISPLAY INVISIBLE (7825 4350);
FORCEPROP 1 LAST PACK_TYPE SMD-BCG5
J 0
(7800 4275);
DISPLAY 0.617021 (7800 4275);
PAINT GREEN (7800 4275);
DISPLAY INVISIBLE (7800 4275);
FORCEADD IND-1UH-361-GP..1
R 1
(10500 4050);
FORCEPROP 2 LAST PACK_SIZE DCR=4.6MOHM
J 0
(10350 3825);
DISPLAY 0.638298 (10350 3825);
PAINT GREEN (10350 3825);
FORCEPROP 2 LAST RATED ISAT=24A@25C
J 0
(10350 3875);
DISPLAY 0.638298 (10350 3875);
PAINT GREEN (10350 3875);
FORCEPROP 1 LAST VALUE IND-1UH-361-GP
J 0
(10350 3975);
DISPLAY 0.617021 (10350 3975);
PAINT GREEN (10350 3975);
FORCEPROP 1 LAST LOCATION L8F1
J 0
(10350 4100);
DISPLAY 0.617021 (10350 4100);
PAINT GREEN (10350 4100);
FORCEPROP 2 LASTPIN (10350 4050) $PN 1
J 2
(10390 4060);
DISPLAY 0.808511 (10390 4060);
PAINT ORANGE (10390 4060);
FORCEPROP 2 LASTPIN (10650 4050) $PN 2
J 0
(10660 4060);
DISPLAY 0.808511 (10660 4060);
PAINT ORANGE (10660 4060);
FORCEPROP 2 LAST ATTRIBUTE 1.0UH
J 0
(10350 3925);
DISPLAY 0.638298 (10350 3925);
PAINT GREEN (10350 3925);
FORCEPROP 1 LAST PACK_TYPE DISCRET-GC1
R 1
J 0
(10500 4050);
DISPLAY 0.617021 (10500 4050);
PAINT GREEN (10500 4050);
DISPLAY INVISIBLE (10500 4050);
FORCEPROP 2 LAST SEC 1
J 0
(10350 4175);
DISPLAY 0.680851 (10350 4175);
PAINT MONO (10350 4175);
DISPLAY INVISIBLE (10350 4175);
FORCEPROP 2 LAST SEC_TYPE DISCRET-GC1
J 0
(10350 4175);
DISPLAY 1.021277 (10350 4175);
PAINT ORANGE (10350 4175);
DISPLAY INVISIBLE (10350 4175);
FORCEPROP 1 LAST PART_NUMBER 068.1R010.1781
R 1
J 0
(10540 4050);
DISPLAY 0.617021 (10540 4050);
PAINT GREEN (10540 4050);
DISPLAY INVISIBLE (10540 4050);
FORCEPROP 2 LAST CDS_LIB w_hdl
R 1
J 0
(10500 4050);
PAINT MONO (10500 4050);
DISPLAY INVISIBLE (10500 4050);
FORCEPROP 1 LAST PATH I188
R 1
J 0
(10460 4050);
DISPLAY 0.617021 (10460 4050);
PAINT GREEN (10460 4050);
DISPLAY INVISIBLE (10460 4050);
FORCEPROP 1 LAST CDS_LMAN_SYM_OUTLINE -50,100,50,-100
R 1
J 0
(10500 4050);
DISPLAY 0.468085 (10500 4050);
PAINT GREEN (10500 4050);
DISPLAY INVISIBLE (10500 4050);
FORCEADD ST470U6D3VDM-7-GP..1
(11100 3825);
FORCEPROP 2 LASTPIN (11100 3900) $PN 1
R 1
J 0
(11090 3910);
DISPLAY 0.808511 (11090 3910);
PAINT ORANGE (11090 3910);
FORCEPROP 1 LAST VALUE ST470U6D3VDM-7-GP
R 1
J 0
(11175 3575);
DISPLAY 0.617021 (11175 3575);
PAINT GREEN (11175 3575);
FORCEPROP 2 LASTPIN (11100 3750) $PN 2
R 1
J 2
(11090 3740);
DISPLAY 0.808511 (11090 3740);
PAINT ORANGE (11090 3740);
FORCEPROP 1 LAST LOCATION C8F14
J 0
(11200 3905);
DISPLAY 0.617021 (11200 3905);
PAINT GREEN (11200 3905);
FORCEPROP 2 LAST ATTRIBUTE 470UF
J 0
(11200 3850);
DISPLAY 0.638298 (11200 3850);
PAINT GREEN (11200 3850);
FORCEPROP 2 LAST TOLERANCE IRP=1.7A
J 0
(11200 3800);
DISPLAY 0.638298 (11200 3800);
PAINT GREEN (11200 3800);
FORCEPROP 2 LAST RATED 6.3V
J 0
(11200 3750);
DISPLAY 0.638298 (11200 3750);
PAINT GREEN (11200 3750);
FORCEPROP 2 LAST TYPE TMAX=105C
J 0
(11200 3700);
DISPLAY 0.638298 (11200 3700);
PAINT GREEN (11200 3700);
FORCEPROP 2 LAST PACK_SIZE ESR=35MOHM
J 0
(11200 3650);
DISPLAY 0.638298 (11200 3650);
PAINT GREEN (11200 3650);
FORCEPROP 1 LAST CDS_LMAN_SYM_OUTLINE -50,25,50,-25
J 0
(11100 3825);
DISPLAY 0.468085 (11100 3825);
PAINT GREEN (11100 3825);
DISPLAY INVISIBLE (11100 3825);
FORCEPROP 1 LAST PATH I189
J 0
(11100 3865);
DISPLAY 0.617021 (11100 3865);
PAINT GREEN (11100 3865);
DISPLAY INVISIBLE (11100 3865);
FORCEPROP 2 LAST CDS_LIB w_hdl
J 0
(11100 3825);
PAINT MONO (11100 3825);
DISPLAY INVISIBLE (11100 3825);
FORCEPROP 1 LAST PART_NUMBER 077.C4771.0061
J 0
(11100 3785);
DISPLAY 0.617021 (11100 3785);
PAINT GREEN (11100 3785);
DISPLAY INVISIBLE (11100 3785);
FORCEPROP 2 LAST SEC_TYPE SMD-TCG4
J 0
(11125 3900);
DISPLAY 1.021277 (11125 3900);
PAINT ORANGE (11125 3900);
DISPLAY INVISIBLE (11125 3900);
FORCEPROP 2 LAST SEC 1
J 0
(11125 3900);
DISPLAY 0.680851 (11125 3900);
PAINT MONO (11125 3900);
DISPLAY INVISIBLE (11125 3900);
FORCEPROP 1 LAST PACK_TYPE SMD-TCG4
J 0
(11100 3825);
DISPLAY 0.617021 (11100 3825);
PAINT GREEN (11100 3825);
DISPLAY INVISIBLE (11100 3825);
FORCEADD ST470U6D3VDM-7-GP..1
(11500 3825);
FORCEPROP 2 LAST TYPE TMAX=105C
J 0
(11600 3700);
DISPLAY 0.638298 (11600 3700);
PAINT GREEN (11600 3700);
FORCEPROP 1 LAST VALUE ST470U6D3VDM-7-GP
R 1
J 0
(11575 3575);
DISPLAY 0.617021 (11575 3575);
PAINT GREEN (11575 3575);
FORCEPROP 2 LAST PACK_SIZE ESR=35MOHM
J 0
(11600 3650);
DISPLAY 0.638298 (11600 3650);
PAINT GREEN (11600 3650);
FORCEPROP 2 LAST RATED 6.3V
J 0
(11600 3750);
DISPLAY 0.638298 (11600 3750);
PAINT GREEN (11600 3750);
FORCEPROP 2 LAST TOLERANCE IRP=1.7A
J 0
(11600 3800);
DISPLAY 0.638298 (11600 3800);
PAINT GREEN (11600 3800);
FORCEPROP 2 LAST ATTRIBUTE 470UF
J 0
(11600 3850);
DISPLAY 0.638298 (11600 3850);
PAINT GREEN (11600 3850);
FORCEPROP 1 LAST LOCATION C8F8
J 0
(11600 3905);
DISPLAY 0.617021 (11600 3905);
PAINT GREEN (11600 3905);
FORCEPROP 2 LASTPIN (11500 3900) $PN 1
R 1
J 0
(11490 3910);
DISPLAY 0.808511 (11490 3910);
PAINT ORANGE (11490 3910);
FORCEPROP 2 LASTPIN (11500 3750) $PN 2
R 1
J 2
(11490 3740);
DISPLAY 0.808511 (11490 3740);
PAINT ORANGE (11490 3740);
FORCEPROP 1 LAST PATH I190
J 0
(11500 3865);
DISPLAY 0.617021 (11500 3865);
PAINT GREEN (11500 3865);
DISPLAY INVISIBLE (11500 3865);
FORCEPROP 1 LAST PACK_TYPE SMD-TCG4
J 0
(11500 3825);
DISPLAY 0.617021 (11500 3825);
PAINT GREEN (11500 3825);
DISPLAY INVISIBLE (11500 3825);
FORCEPROP 2 LAST SEC 1
J 0
(11525 3900);
DISPLAY 0.680851 (11525 3900);
PAINT MONO (11525 3900);
DISPLAY INVISIBLE (11525 3900);
FORCEPROP 2 LAST SEC_TYPE SMD-TCG4
J 0
(11525 3900);
DISPLAY 1.021277 (11525 3900);
PAINT ORANGE (11525 3900);
DISPLAY INVISIBLE (11525 3900);
FORCEPROP 1 LAST PART_NUMBER 077.C4771.0061
J 0
(11500 3785);
DISPLAY 0.617021 (11500 3785);
PAINT GREEN (11500 3785);
DISPLAY INVISIBLE (11500 3785);
FORCEPROP 2 LAST CDS_LIB w_hdl
J 0
(11500 3825);
PAINT MONO (11500 3825);
DISPLAY INVISIBLE (11500 3825);
FORCEPROP 1 LAST CDS_LMAN_SYM_OUTLINE -50,25,50,-25
J 0
(11500 3825);
DISPLAY 0.468085 (11500 3825);
PAINT GREEN (11500 3825);
DISPLAY INVISIBLE (11500 3825);
FORCEADD SC4D7U16V3KX-GP..1
(5500 3275);
FORCEPROP 2 LASTPIN (5500 3350) $PN 1
R 1
J 0
(5490 3360);
DISPLAY 0.808511 (5490 3360);
PAINT ORANGE (5490 3360);
FORCEPROP 1 LAST LOCATION C2R11
J 0
(5550 3355);
DISPLAY 0.617021 (5550 3355);
PAINT GREEN (5550 3355);
FORCEPROP 1 LAST VALUE SC4D7U16V3KX-GP
J 0
(5550 3300);
DISPLAY 0.617021 (5550 3300);
PAINT GREEN (5550 3300);
FORCEPROP 2 LAST ATTRIBUTE 4.7UF
J 0
(5550 3250);
DISPLAY 0.638298 (5550 3250);
PAINT GREEN (5550 3250);
FORCEPROP 2 LAST TOLERANCE 10%
J 0
(5550 3200);
DISPLAY 0.638298 (5550 3200);
PAINT GREEN (5550 3200);
FORCEPROP 2 LASTPIN (5500 3200) $PN 2
R 1
J 2
(5490 3190);
DISPLAY 0.808511 (5490 3190);
PAINT ORANGE (5490 3190);
FORCEPROP 2 LAST RATED 16V
J 0
(5550 3150);
DISPLAY 0.638298 (5550 3150);
PAINT GREEN (5550 3150);
FORCEPROP 2 LAST PACK_SIZE 0603
J 0
(5550 3100);
DISPLAY 0.638298 (5550 3100);
PAINT GREEN (5550 3100);
FORCEPROP 1 LAST CDS_LMAN_SYM_OUTLINE -50,25,50,-25
J 0
(5500 3275);
DISPLAY 0.468085 (5500 3275);
PAINT GREEN (5500 3275);
DISPLAY INVISIBLE (5500 3275);
FORCEPROP 1 LAST PATH I191
J 0
(5500 3275);
DISPLAY 0.617021 (5500 3275);
PAINT GREEN (5500 3275);
DISPLAY INVISIBLE (5500 3275);
FORCEPROP 2 LAST CDS_LIB w_hdl
J 0
(5500 3275);
PAINT MONO (5500 3275);
DISPLAY INVISIBLE (5500 3275);
FORCEPROP 1 LAST PART_NUMBER 078.47521.08BD
J 0
(5500 3275);
DISPLAY 0.617021 (5500 3275);
PAINT GREEN (5500 3275);
DISPLAY INVISIBLE (5500 3275);
FORCEPROP 2 LAST SEC_TYPE SMD-BCG5
J 0
(5525 3350);
DISPLAY 1.021277 (5525 3350);
PAINT ORANGE (5525 3350);
DISPLAY INVISIBLE (5525 3350);
FORCEPROP 2 LAST SEC 1
J 0
(5525 3350);
DISPLAY 0.680851 (5525 3350);
PAINT MONO (5525 3350);
DISPLAY INVISIBLE (5525 3350);
FORCEPROP 1 LAST PACK_TYPE SMD-BCG5
J 0
(5500 3275);
DISPLAY 0.617021 (5500 3275);
PAINT GREEN (5500 3275);
DISPLAY INVISIBLE (5500 3275);
FORCEADD BLM31SN500SN1L-GP..1
R 1
(6100 4500);
FORCEPROP 1 LAST VALUE BLM31SN500SN1L-GP
J 0
(5949 4450);
DISPLAY 0.617021 (5949 4450);
PAINT GREEN (5949 4450);
FORCEPROP 2 LAST PACK_SIZE DCR=1.6MOHM
J 0
(5950 4400);
DISPLAY 0.638298 (5950 4400);
PAINT GREEN (5950 4400);
FORCEPROP 2 LAST RATED 1MA
J 0
(5950 4350);
DISPLAY 0.638298 (5950 4350);
PAINT GREEN (5950 4350);
FORCEPROP 2 LASTPIN (5950 4500) $PN 1
J 2
(5940 4510);
DISPLAY 0.808511 (5940 4510);
PAINT ORANGE (5940 4510);
FORCEPROP 1 LAST LOCATION FB9E1
J 0
(5950 4575);
DISPLAY 0.617021 (5950 4575);
PAINT GREEN (5950 4575);
FORCEPROP 2 LASTPIN (6250 4500) $PN 2
J 0
(6260 4510);
DISPLAY 0.808511 (6260 4510);
PAINT ORANGE (6260 4510);
FORCEPROP 2 LAST ATTRIBUTE 50OHM@100MHZ
J 0
(5950 4300);
DISPLAY 0.638298 (5950 4300);
PAINT GREEN (5950 4300);
FORCEPROP 1 LAST PACK_TYPE DISCRET-GB1
R 1
J 0
(6100 4500);
DISPLAY 0.617021 (6100 4500);
PAINT GREEN (6100 4500);
DISPLAY INVISIBLE (6100 4500);
FORCEPROP 2 LAST SEC 1
J 0
(5950 4625);
DISPLAY 0.680851 (5950 4625);
PAINT MONO (5950 4625);
DISPLAY INVISIBLE (5950 4625);
FORCEPROP 2 LAST SEC_TYPE DISCRET-GB1
J 0
(5950 4625);
DISPLAY 1.021277 (5950 4625);
PAINT ORANGE (5950 4625);
DISPLAY INVISIBLE (5950 4625);
FORCEPROP 1 LAST PART_NUMBER 068.00007.0011
R 1
J 0
(6101 4500);
DISPLAY 0.617021 (6101 4500);
PAINT GREEN (6101 4500);
DISPLAY INVISIBLE (6101 4500);
FORCEPROP 2 LAST CDS_LIB w_hdl
R 1
J 0
(6100 4500);
DISPLAY INVISIBLE (6100 4500);
FORCEPROP 1 LAST PATH I193
R 1
J 0
(6100 4500);
DISPLAY 0.617021 (6100 4500);
PAINT GREEN (6100 4500);
DISPLAY INVISIBLE (6100 4500);
FORCEPROP 1 LAST CDS_LMAN_SYM_OUTLINE -50,100,50,-100
R 1
J 0
(6100 4500);
DISPLAY 0.468085 (6100 4500);
PAINT GREEN (6100 4500);
DISPLAY INVISIBLE (6100 4500);
FORCEADD RES..2
(6450 1850);
FORCEPROP 1 LAST VALUE 49.9K
J 0
(6495 1925);
DISPLAY 0.617021 (6495 1925);
PAINT SKYBLUE (6495 1925);
FORCEPROP 1 LAST TOLERANCE 1%
J 0
(6495 1875);
DISPLAY 0.617021 (6495 1875);
PAINT SKYBLUE (6495 1875);
FORCEPROP 1 LAST WATTAGE 1/16W
J 0
(6490 1825);
DISPLAY 0.617021 (6490 1825);
PAINT SKYBLUE (6490 1825);
FORCEPROP 1 LASTPIN (6450 1950) $PN 1
J 0
(6455 1912);
DISPLAY 0.787234 (6455 1912);
PAINT ORANGE (6455 1912);
FORCEPROP 1 LAST MATERIAL CHIP
J 0
(6490 1775);
DISPLAY 0.617021 (6490 1775);
PAINT SKYBLUE (6490 1775);
FORCEPROP 1 LASTPIN (6450 1750) $PN 2
J 0
(6455 1760);
DISPLAY 0.787234 (6455 1760);
PAINT ORANGE (6455 1760);
FORCEPROP 1 LAST PACK_TYPE 0402
J 0
(6490 1675);
DISPLAY 0.617021 (6490 1675);
PAINT SKYBLUE (6490 1675);
FORCEPROP 1 LAST PART_NUMBER G21796-048
J 0
(6490 1725);
DISPLAY 0.617021 (6490 1725);
PAINT BLUE (6490 1725);
FORCEPROP 1 LAST LOCATION R8F9
J 0
(6495 1975);
DISPLAY 0.617021 (6495 1975);
PAINT AQUA (6495 1975);
FORCEPROP 2 LAST CDS_LIB mstr_discrete
J 0
(6450 1850);
PAINT MONO (6450 1850);
DISPLAY INVISIBLE (6450 1850);
FORCEPROP 2 LAST ROOM V_SUPER
J 0
(6500 2025);
DISPLAY 1.021277 (6500 2025);
PAINT ORANGE (6500 2025);
DISPLAY INVISIBLE (6500 2025);
FORCEPROP 2 LAST SEC_TYPE 0402
J 0
(6500 2075);
DISPLAY 1.021277 (6500 2075);
PAINT ORANGE (6500 2075);
DISPLAY INVISIBLE (6500 2075);
FORCEPROP 0 LAST SEC 1
J 0
(6500 2025);
DISPLAY 0.680851 (6500 2025);
PAINT MONO (6500 2025);
DISPLAY INVISIBLE (6500 2025);
FORCEPROP 1 LAST PATH I195
J 0
(6500 2025);
DISPLAY 0.978723 (6500 2025);
PAINT WHITE (6500 2025);
DISPLAY INVISIBLE (6500 2025);
FORCEADD P3V3_STBY..1
(12575 4225);
FORCEPROP 3 LASTPIN (12575 4175) SIG_NAME P3V3_STBY\g
J 0
(12585 4185);
DISPLAY 0.659574 (12585 4185);
PAINT MONO (12585 4185);
DISPLAY INVISIBLE (12585 4185);
FORCEPROP 1 LAST PATH I85
J 0
(12620 4227);
DISPLAY 0.340426 (12620 4227);
PAINT GREEN (12620 4227);
DISPLAY INVISIBLE (12620 4227);
FORCEPROP 2 LAST CDS_LIB mstr_symbols
J 0
(12575 4225);
PAINT ORANGE (12575 4225);
DISPLAY INVISIBLE (12575 4225);
FORCEPROP 1 LAST SIZE 1B
J 0
(12620 4247);
DISPLAY 0.340426 (12620 4247);
PAINT GREEN (12620 4247);
DISPLAY INVISIBLE (12620 4247);
FORCEPROP 1 LAST VOLTAGE +3.3V
J 0
(12775 4375);
DISPLAY 1.021277 (12775 4375);
PAINT SKYBLUE (12775 4375);
DISPLAY INVISIBLE (12775 4375);
FORCEPROP 1 LAST BODY_TYPE PLUMBING
J 0
(12530 4182);
DISPLAY 0.340426 (12530 4182);
PAINT GREEN (12530 4182);
DISPLAY INVISIBLE (12530 4182);
FORCEPROP 1 LAST HDL_POWER P3V3_STBY
J 0
(12275 4100);
DISPLAY 0.872340 (12275 4100);
PAINT ORANGE (12275 4100);
DISPLAY INVISIBLE (12275 4100);
FORCEADD DNS..2
(9755 3895);
PAINT RED (9755 3895);
FORCEPROP 2 LAST CDS_LIB mstr_misc
J 0
(9755 3895);
PAINT ORANGE (9755 3895);
DISPLAY INVISIBLE (9755 3895);
FORCEPROP 1 LAST COMMENT_BODY TRUE
R 1
J 0
(9830 3670);
DISPLAY 0.872340 (9830 3670);
PAINT GREEN (9830 3670);
DISPLAY INVISIBLE (9830 3670);
FORCEADD DNS..2
(5630 2395);
PAINT RED (5630 2395);
FORCEPROP 2 LAST CDS_LIB mstr_misc
J 0
(5630 2395);
PAINT ORANGE (5630 2395);
DISPLAY INVISIBLE (5630 2395);
FORCEPROP 1 LAST COMMENT_BODY TRUE
R 1
J 0
(5705 2170);
DISPLAY 0.872340 (5705 2170);
PAINT GREEN (5705 2170);
DISPLAY INVISIBLE (5705 2170);
FORCEADD DNS..2
(6180 2470);
PAINT RED (6180 2470);
FORCEPROP 2 LAST CDS_LIB mstr_misc
J 0
(6180 2470);
PAINT ORANGE (6180 2470);
DISPLAY INVISIBLE (6180 2470);
FORCEPROP 1 LAST COMMENT_BODY TRUE
R 1
J 0
(6255 2245);
DISPLAY 0.872340 (6255 2245);
PAINT GREEN (6255 2245);
DISPLAY INVISIBLE (6255 2245);
FORCEADD DNS..2
(6955 3245);
PAINT RED (6955 3245);
FORCEPROP 2 LAST CDS_LIB mstr_misc
J 0
(6955 3245);
PAINT ORANGE (6955 3245);
DISPLAY INVISIBLE (6955 3245);
FORCEPROP 1 LAST COMMENT_BODY TRUE
R 1
J 0
(7030 3020);
DISPLAY 0.872340 (7030 3020);
PAINT GREEN (7030 3020);
DISPLAY INVISIBLE (7030 3020);
FORCEADD INTEL_CORP_BPAGE..1
(12800 175);
FORCEPROP 1 LAST CDS_CON_LAST_MODIFIED Fri Jun 16 17:49:25 2017
J 0
(11375 500);
PAINT ORANGE (11375 500);
DISPLAY INVISIBLE (11375 500);
FORCEPROP 1 LAST CUSTOM_TXT_CDS <CURRENT_DESIGN_SHEET> OF <TOTAL_DESIGN_SHEETS>
J 0
(12300 200);
PAINT ORANGE (12300 200);
FORCEPROP 1 LAST CUSTOM_TXT_CDS <CON_LAST_MODIFIED>
J 0
(8800 275);
PAINT ORANGE (8800 275);
FORCEPROP 2 LAST CUSTOM_TXT_CDS <XR_PAGE_TITLE>
J 0
(4910 5425);
DISPLAY 0.638298 (4910 5425);
PAINT PINK (4910 5425);
DISPLAY INVISIBLE (4910 5425);
FORCEPROP 1 LAST SCH_TITLE P3V3 STBY VR
J 0
(4850 225);
DISPLAY 1.212766 (4850 225);
PAINT ORANGE (4850 225);
FORCEPROP 2 LAST PAGE_BORDER TRUE
J 0
(4910 5425);
DISPLAY 0.851064 (4910 5425);
PAINT PINK (4910 5425);
DISPLAY INVISIBLE (4910 5425);
FORCEPROP 2 LAST CDS_LIB mstr_symbols
J 0
(12800 175);
PAINT MONO (12800 175);
DISPLAY INVISIBLE (12800 175);
FORCEPROP 1 LAST COMMENT_BODY TRUE
J 0
(12812 187);
DISPLAY 0.468085 (12812 187);
PAINT GREEN (12812 187);
DISPLAY INVISIBLE (12812 187);
FORCEPROP 2 LAST CDS_XR_PAGE_TITLE CR-240 : @BASEBOARD_FAB2_LIB.BASEBOARD_FAB2(SCH_1):PAGE240
J 0
(4910 5425);
DISPLAY 0.638298 (4910 5425);
PAINT PINK (4910 5425);
DISPLAY INVISIBLE (4910 5425);
FORCEADD DESIGN_NOTE..1
(11450 4875);
FORCEPROP 2 LAST CDS_LIB mstr_symbols
J 0
(11450 4875);
DISPLAY 1.021277 (11450 4875);
PAINT WHITE (11450 4875);
DISPLAY INVISIBLE (11450 4875);
FORCEPROP 1 LAST COMMENT_BODY TRUE
J 0
(11475 4975);
DISPLAY 1.361702 (11475 4975);
PAINT WHITE (11475 4975);
DISPLAY INVISIBLE (11475 4975);
FORCEADD DNS..2
(9755 3545);
PAINT RED (9755 3545);
FORCEPROP 2 LAST CDS_LIB mstr_misc
J 0
(9755 3545);
PAINT ORANGE (9755 3545);
DISPLAY INVISIBLE (9755 3545);
FORCEPROP 1 LAST COMMENT_BODY TRUE
R 1
J 0
(9830 3320);
DISPLAY 0.872340 (9830 3320);
PAINT GREEN (9830 3320);
DISPLAY INVISIBLE (9830 3320);
WIRE 16 -1 (5625 2200)(5625 2300);
WIRE 16 -1 (5725 3500)(5725 3550);
WIRE 16 -1 (6025 3500)(5725 3500);
WIRE 16 -1 (5500 3500)(5725 3500);
WIRE 16 -1 (5500 3350)(5500 3500);
WIRE 16 -1 (6025 2875)(6025 3500);
WIRE 16 -1 (7150 2875)(6025 2875);
WIRE 16 -1 (6350 3250)(6350 3150);
WIRE 16 -1 (8475 4200)(8475 4250);
WIRE 16 -1 (6275 4100)(6275 4000);
WIRE 16 -1 (5700 4700)(5700 4500);
WIRE 16 -1 (5700 4500)(5950 4500);
WIRE 16 -1 (10175 1675)(10175 1725);
WIRE 16 -1 (10175 1725)(10375 1725);
WIRE 16 -1 (9650 3200)(9650 3250);
WIRE 16 -1 (9650 3250)(9550 3250);
WIRE 16 -1 (9750 3450)(9750 3400);
WIRE 16 -1 (10750 3600)(10750 3700);
WIRE 16 -1 (11100 3750)(11100 3600);
WIRE 16 -1 (11500 3750)(11500 3600);
WIRE 16 -1 (11950 3650)(11950 3775);
WIRE 16 -1 (12175 3650)(12175 3775);
WIRE 16 -1 (6975 2375)(6975 2150);
WIRE 16 -1 (6975 2425)(6975 2375);
WIRE 16 -1 (7150 2375)(6975 2375);
WIRE 16 -1 (6975 2675)(6975 2425);
WIRE 16 -1 (7150 2425)(6975 2425);
WIRE 16 -1 (7150 2675)(6975 2675);
WIRE 16 -1 (6450 1750)(6450 1600);
WIRE 16 -1 (6175 2225)(6175 2375);
WIRE 16 -1 (5500 3200)(5500 3150);
WIRE 16 -1 (9475 925)(9475 850);
WIRE 16 -1 (9325 925)(9475 925);
WIRE 16 -1 (9475 925)(9475 1000);
WIRE 16 -1 (10725 1675)(10725 1725);
WIRE 16 -1 (10725 1725)(10575 1725);
WIRE 16 -1 (12425 3775)(12425 3625);
WIRE 16 -1 (6950 3350)(6950 3450);
WIRE 16 -1 (6700 4200)(6700 4075);
WIRE 16 -1 (7450 4200)(7450 4075);
WIRE 16 -1 (7800 4200)(7800 4075);
WIRE 16 -1 (7000 4200)(7000 4075);
WIRE 16 -1 (12575 4175)(12575 4050);
WIRE 16 -1 (12575 4050)(12425 4050);
WIRE 16 -1 (12575 4050)(12575 2025);
WIRE 16 -1 (9525 2025)(12575 2025);
WIRE 16 -1 (12425 4050)(12175 4050);
WIRE 16 -1 (12425 3975)(12425 4050);
WIRE 16 -1 (11950 4050)(12175 4050);
WIRE 16 -1 (12175 4050)(12175 3975);
WIRE 16 -1 (9525 2025)(9525 1900);
WIRE 16 -1 (11950 4050)(11500 4050);
WIRE 16 -1 (11950 4050)(11950 3975);
WIRE 16 -1 (11500 4050)(11100 4050);
WIRE 16 -1 (11500 4050)(11500 3900);
WIRE 16 -1 (11100 4050)(10750 4050);
WIRE 16 -1 (11100 4050)(11100 3900);
WIRE 16 -1 (10650 4050)(10750 4050);
WIRE 16 -1 (10750 3900)(10750 4050);
WIRE 3 682 (5850 4650)(5850 4250);
WIRE 3 682 (6450 4650)(5850 4650);
WIRE 3 682 (5850 4250)(6450 4250);
WIRE 3 682 (6450 4250)(6450 4650);
WIRE 3 682 (5300 3000)(5950 3000);
WIRE 3 682 (5300 3450)(5300 3000);
WIRE 3 682 (5950 3000)(5950 3450);
WIRE 3 682 (5950 3450)(5300 3450);
WIRE 16 -1 (7150 2825)(6175 2825);
WIRE 16 -1 (6175 2825)(6175 3600);
WIRE 16 -1 (6175 3600)(6275 3600);
WIRE 16 -1 (6275 3800)(6275 3600);
WIRE 16 -1 (6350 3450)(6350 3600);
WIRE 16 -1 (6350 3600)(6275 3600);
WIRE 16 -1 (6350 3825)(6350 3600);
WIRE 16 -1 (7075 3825)(6350 3825);
FORCEPROP 2 LAST SIG_NAME PWRGD_P3V3_STBY_R
J 0
(6515 3835);
DISPLAY 0.617021 (6515 3835);
PAINT ORANGE (6515 3835);
FORCEPROP 2 LASTPROP $XRERR UNIQUE?
J 0
(6275 3835);
DISPLAY 0.638298 (6275 3835);
PAINT MONO (6275 3835);
DISPLAY INVISIBLE (6275 3835);
WIRE 16 2175 (6550 4550)(8400 4550);
WIRE 16 2175 (8400 4550)(8400 3950);
WIRE 16 2175 (6550 3950)(6550 4550);
WIRE 16 2175 (6550 3950)(8400 3950);
WIRE 68 -1 (6600 4000)(6600 4600);
WIRE 68 -1 (6600 4600)(7300 4600);
WIRE 68 -1 (6600 4000)(7300 4000);
WIRE 68 -1 (7300 4000)(7300 4600);
WIRE 16 2175 (9400 900)(9775 900);
WIRE 16 2175 (9775 1950)(9775 900);
WIRE 16 2175 (9400 900)(9400 1950);
WIRE 16 2175 (9400 1950)(9775 1950);
WIRE 16 -1 (8200 3425)(7700 3425);
FORCEPROP 2 LAST SIG_NAME VR_P3V3_STBY_BOOT_R
J 0
(7720 3435);
DISPLAY 0.617021 (7720 3435);
PAINT ORANGE (7720 3435);
FORCEPROP 2 LASTPROP $XRERR UNIQUE?
J 0
(7480 3435);
DISPLAY 0.638298 (7480 3435);
PAINT MONO (7480 3435);
DISPLAY INVISIBLE (7480 3435);
WIRE 16 -1 (7950 2375)(8275 2375);
WIRE 16 -1 (8275 2375)(8275 925);
WIRE 16 -1 (9125 925)(8275 925);
FORCEPROP 2 LAST SIG_NAME VSENSE_RGND_P3V3_STBY
J 0
(8290 935);
DISPLAY 0.617021 (8290 935);
PAINT ORANGE (8290 935);
FORCEPROP 2 LASTPROP $XRERR UNIQUE?
J 0
(8050 935);
DISPLAY 0.638298 (8050 935);
PAINT MONO (8050 935);
DISPLAY INVISIBLE (8050 935);
WIRE 16 -1 (6175 2575)(6175 2725);
WIRE 16 -1 (6300 2725)(6175 2725);
WIRE 16 -1 (5625 2500)(5625 2725);
WIRE 16 -1 (5625 2725)(6175 2725);
WIRE 16 -1 (5225 2725)(5625 2725);
FORCEPROP 2 LAST SIG_NAME PWRGD_P5V_STBY
J 0
(5216 2747);
DISPLAY 0.617021 (5216 2747);
PAINT ORANGE (5216 2747);
WIRE 16 -1 (9475 1250)(9475 1200);
WIRE 16 -1 (9475 1325)(9475 1250);
WIRE 16 -1 (8400 1250)(9475 1250);
FORCEPROP 0 LAST SIG_NAME VSENSE_VOUT_P3V3_STBY
J 0
(8415 1260);
DISPLAY 0.617021 (8415 1260);
PAINT ORANGE (8415 1260);
FORCEPROP 2 LASTPROP $XRERR UNIQUE?
J 0
(8175 1260);
DISPLAY 0.638298 (8175 1260);
PAINT MONO (8175 1260);
DISPLAY INVISIBLE (8175 1260);
WIRE 16 -1 (7950 2475)(8400 2475);
WIRE 16 -1 (8400 2475)(8400 1250);
WIRE 16 -1 (8000 2875)(7950 2875);
WIRE 16 -1 (8000 3125)(8000 2875);
WIRE 16 -1 (7375 3125)(8000 3125);
WIRE 16 -1 (7375 3425)(7375 3125);
FORCEPROP 2 LAST SIG_NAME VR_P3V3_STBY_BOOT
J 0
(7465 3160);
DISPLAY 0.617021 (7465 3160);
PAINT ORANGE (7465 3160);
FORCEPROP 2 LASTPROP $XRERR UNIQUE?
J 0
(7225 3160);
DISPLAY 0.638298 (7225 3160);
PAINT MONO (7225 3160);
DISPLAY INVISIBLE (7225 3160);
WIRE 16 -1 (7500 3425)(7375 3425);
WIRE 16 -1 (7775 3825)(7275 3825);
FORCEPROP 2 LAST SIG_NAME PWRGD_P3V3_STBY
J 0
(7340 3835);
DISPLAY 0.617021 (7340 3835);
PAINT ORANGE (7340 3835);
WIRE 16 -1 (6950 2725)(6500 2725);
FORCEPROP 2 LAST SIG_NAME VR_P3V3_STBY_EN
J 0
(6565 2735);
DISPLAY 0.617021 (6565 2735);
PAINT ORANGE (6565 2735);
FORCEPROP 2 LASTPROP $XRERR UNIQUE?
J 0
(6325 2735);
DISPLAY 0.638298 (6325 2735);
PAINT MONO (6325 2735);
DISPLAY INVISIBLE (6325 2735);
WIRE 16 -1 (7150 2725)(6950 2725);
WIRE 16 -1 (6950 2725)(6950 3150);
WIRE 16 -1 (9525 1650)(9525 1700);
WIRE 16 -1 (9525 1650)(9475 1650);
WIRE 16 -1 (9475 1525)(9475 1650);
FORCEPROP 0 LAST SIG_NAME VSENSE_P3V3_STBY
R 1
J 0
(9440 1485);
DISPLAY 0.617021 (9440 1485);
PAINT ORANGE (9440 1485);
FORCEPROP 2 LASTPROP $XRERR UNIQUE?
J 0
(9200 1485);
DISPLAY 0.638298 (9200 1485);
PAINT MONO (9200 1485);
DISPLAY INVISIBLE (9200 1485);
WIRE 68 -1 (8100 4000)(8100 4600);
WIRE 68 -1 (7350 4600)(8100 4600);
WIRE 68 -1 (7350 4000)(8100 4000);
WIRE 68 -1 (7350 4000)(7350 4600);
WIRE 16 -1 (8600 3400)(8950 3400);
WIRE 16 -1 (8600 2775)(8600 3400);
WIRE 16 -1 (7950 2775)(8600 2775);
FORCEPROP 2 LAST SIG_NAME VR_P3V3_STBY_UGATE
J 0
(8090 2785);
DISPLAY 0.617021 (8090 2785);
PAINT ORANGE (8090 2785);
FORCEPROP 2 LASTPROP $XRERR UNIQUE?
J 0
(7850 2785);
DISPLAY 0.638298 (7850 2785);
PAINT MONO (7850 2785);
DISPLAY INVISIBLE (7850 2785);
WIRE 16 -1 (8800 3300)(8950 3300);
WIRE 16 -1 (8800 2575)(8800 3300);
WIRE 16 -1 (7950 2575)(8800 2575);
FORCEPROP 2 LAST SIG_NAME VR_P3V3_STBY_LGATE
J 0
(8165 2585);
DISPLAY 0.617021 (8165 2585);
PAINT ORANGE (8165 2585);
FORCEPROP 2 LASTPROP $XRERR UNIQUE?
J 0
(7925 2585);
DISPLAY 0.638298 (7925 2585);
PAINT MONO (7925 2585);
DISPLAY INVISIBLE (7925 2585);
WIRE 16 -1 (9750 3650)(9750 3800);
FORCEPROP 2 LAST SIG_NAME VR_P3V3_STBY_SNUB
J 0
(9765 3710);
DISPLAY 0.617021 (9765 3710);
PAINT ORANGE (9765 3710);
FORCEPROP 2 LASTPROP $XRERR UNIQUE?
J 0
(9525 3710);
DISPLAY 0.638298 (9525 3710);
PAINT MONO (9525 3710);
DISPLAY INVISIBLE (9525 3710);
WIRE 3 273 (10300 3800)(10700 3800);
WIRE 3 273 (10300 4150)(10300 3800);
WIRE 3 273 (10700 3800)(10700 4150);
WIRE 3 273 (10700 4150)(10300 4150);
WIRE 16 682 (11225 4950)(11225 4325);
WIRE 16 682 (12025 4950)(11225 4950);
WIRE 16 682 (11225 4325)(12025 4325);
WIRE 16 682 (12025 4325)(12025 4950);
WIRE 3 682 (11050 3500)(11900 3500);
WIRE 3 682 (11050 4100)(11050 3500);
WIRE 3 682 (11900 3500)(11900 4100);
WIRE 3 682 (11900 4100)(11050 4100);
WIRE 16 -1 (6450 2325)(7150 2325);
FORCEPROP 2 LAST SIG_NAME VR_P3V3_STBY_OCSELECT
J 0
(6465 2335);
DISPLAY 0.617021 (6465 2335);
PAINT ORANGE (6465 2335);
FORCEPROP 2 LASTPROP $XRERR UNIQUE?
J 0
(6225 2335);
DISPLAY 0.638298 (6225 2335);
PAINT MONO (6225 2335);
DISPLAY INVISIBLE (6225 2335);
WIRE 16 -1 (6450 1950)(6450 2325);
WIRE 3 682 (6400 1650)(6750 1650);
WIRE 3 682 (6400 2050)(6400 1650);
WIRE 3 682 (6750 1650)(6750 2050);
WIRE 3 682 (6750 2050)(6400 2050);
WIRE 16 2175 (7275 3225)(7275 3600);
WIRE 16 2175 (8500 3225)(7275 3225);
WIRE 16 2175 (7275 3600)(8500 3600);
WIRE 16 2175 (8500 3600)(8500 3225);
WIRE 16 -1 (7950 2675)(8450 2675);
WIRE 16 -1 (8450 2675)(8450 3425);
WIRE 16 -1 (8400 3425)(8450 3425);
WIRE 16 -1 (9750 4000)(9750 4050);
WIRE 16 -1 (10350 4050)(9750 4050);
WIRE 16 -1 (9650 3350)(9550 3350);
WIRE 16 -1 (9650 4050)(9650 3350);
WIRE 16 -1 (9750 4050)(9650 4050);
WIRE 16 -1 (8450 4050)(8450 3425);
WIRE 16 -1 (8450 4050)(9650 4050);
FORCEPROP 2 LAST SIG_NAME VR_P3V3_STBY_PHASE
J 0
(8840 4060);
DISPLAY 0.617021 (8840 4060);
PAINT ORANGE (8840 4060);
FORCEPROP 2 LASTPROP $XRERR UNIQUE?
J 0
(8600 4060);
DISPLAY 0.638298 (8600 4060);
PAINT MONO (8600 4060);
DISPLAY INVISIBLE (8600 4060);
WIRE 16 -1 (6700 4500)(6250 4500);
WIRE 16 -1 (6700 4350)(6700 4500);
WIRE 16 -1 (7000 4500)(6700 4500);
WIRE 16 -1 (7000 4500)(7000 4350);
WIRE 16 -1 (7450 4500)(7000 4500);
WIRE 16 -1 (7450 4350)(7450 4500);
WIRE 16 -1 (7800 4500)(7450 4500);
WIRE 16 -1 (7800 4500)(7800 4350);
WIRE 16 -1 (8150 4500)(7800 4500);
WIRE 16 -1 (8150 4425)(8150 4500);
WIRE 16 -1 (8750 3500)(8950 3500);
WIRE 16 -1 (8750 4500)(8750 3500);
WIRE 16 -1 (8475 4500)(8150 4500);
FORCEPROP 0 LAST SIG_NAME VR_FET_SW_P12V_STBY_P3V3_STBY
J 0
(8165 4510);
DISPLAY 0.617021 (8165 4510);
PAINT ORANGE (8165 4510);
FORCEPROP 2 LASTPROP $XRERR UNIQUE?
J 0
(7925 4510);
DISPLAY 0.638298 (7925 4510);
PAINT MONO (7925 4510);
DISPLAY INVISIBLE (7925 4510);
WIRE 16 -1 (8475 4450)(8475 4500);
WIRE 16 -1 (8475 4500)(8750 4500);
DOT 1 (7000 4500);
DOT 1 (6700 4500);
DOT 1 (7450 4500);
DOT 1 (7800 4500);
DOT 1 (8150 4500);
DOT 1 (12175 4050);
DOT 1 (8475 4500);
DOT 1 (5625 2725);
DOT 1 (5725 3500);
DOT 1 (6175 2725);
DOT 1 (6975 2375);
DOT 1 (6975 2425);
DOT 1 (6950 2725);
DOT 1 (6275 3600);
DOT 1 (9475 925);
DOT 1 (9475 1250);
DOT 1 (8450 3425);
DOT 1 (12575 4050);
DOT 1 (6350 3600);
DOT 1 (11950 4050);
DOT 1 (12425 4050);
DOT 1 (9750 4050);
DOT 1 (9650 4050);
DOT 1 (10750 4050);
DOT 1 (11100 4050);
DOT 1 (11500 4050);
FORCENOTE
P3V3_STBY _VOLTAGE SENSE
(8580 680) 0;
DISPLAY LEFT (8580 680);
PAINT PURPLE (8580 680);
FORCENOTE
TP FAB1 CHANGE PN 0310
(5300 2950) 0;
DISPLAY LEFT (5300 2950);
DISPLAY 0.638298 (5300 2950);
PAINT RED (5300 2950);
FORCENOTE
PUT TOGETHER
(6600 4600) 0;
DISPLAY LEFT (6600 4600);
DISPLAY 0.808511 (6600 4600);
PAINT PURPLE (6600 4600);
FORCENOTE
TP FAB3 CHANGE BEAD 0803
(5850 4700) 0;
DISPLAY LEFT (5850 4700);
DISPLAY 1.021277 (5850 4700);
PAINT RED (5850 4700);
FORCENOTE
PUT TOGETHER
(7350 4600) 0;
DISPLAY LEFT (7350 4600);
DISPLAY 0.808511 (7350 4600);
PAINT PURPLE (7350 4600);
FORCENOTE
PLACE ON
(7575 3650) 0;
DISPLAY LEFT (7575 3650);
DISPLAY 1.042553 (7575 3650);
PAINT PURPLE (7575 3650);
FORCENOTE
SPOF
(7275 3625) 0;
DISPLAY LEFT (7275 3625);
DISPLAY 1.659574 (7275 3625);
PAINT PURPLE (7275 3625);
FORCENOTE
SPOF
(9645 1450) 0;
DISPLAY LEFT (9645 1450);
DISPLAY 2.340426 (9645 1450);
PAINT PURPLE (9645 1450);
FORCENOTE
TOP LAYER
(7950 3650) 0;
DISPLAY LEFT (7950 3650);
DISPLAY 1.042553 (7950 3650);
PAINT PURPLE (7950 3650);
FORCENOTE
10MIL WIDTH
(9180 530) 0;
DISPLAY LEFT (9180 530);
DISPLAY 0.808511 (9180 530);
PAINT PURPLE (9180 530);
FORCENOTE
BOM_COST: P3V3_STBY_VR
(5675 225) 0;
DISPLAY LEFT (5675 225);
DISPLAY 0.787234 (5675 225);
PAINT PURPLE (5675 225);
FORCENOTE
ROOM = P3V3_STBY_VR
(5675 275) 0;
DISPLAY LEFT (5675 275);
DISPLAY 0.787234 (5675 275);
PAINT PURPLE (5675 275);
FORCENOTE
5MIL SPACING
(8755 530) 0;
DISPLAY LEFT (8755 530);
DISPLAY 0.808511 (8755 530);
PAINT PURPLE (8755 530);
FORCENOTE
ROUTE VSENSE_RGND_P3V3_STBY/VSENSE_P3V3_STBY AS DIFF PAIR
(8430 605) 0;
DISPLAY LEFT (8430 605);
DISPLAY 0.808511 (8430 605);
PAINT PURPLE (8430 605);
FORCENOTE
CONNECT AT SINGLE
(10175 1925) 0;
DISPLAY LEFT (10175 1925);
DISPLAY 1.042553 (10175 1925);
PAINT PURPLE (10175 1925);
FORCENOTE
VOUT=3.3V
(11275 4730) 0;
DISPLAY LEFT (11275 4730);
DISPLAY 0.617021 (11275 4730);
PAINT PURPLE (11275 4730);
FORCENOTE
RIPPLE=+-1%
(11275 4630) 0;
DISPLAY LEFT (11275 4630);
DISPLAY 0.617021 (11275 4630);
PAINT PURPLE (11275 4630);
FORCENOTE
STEP=6A
(11275 4530) 0;
DISPLAY LEFT (11275 4530);
DISPLAY 0.617021 (11275 4530);
PAINT PURPLE (11275 4530);
FORCENOTE
SW FREQ=  500 KHZ
(11275 4430) 0;
DISPLAY LEFT (11275 4430);
DISPLAY 0.617021 (11275 4430);
PAINT PURPLE (11275 4430);
FORCENOTE
IOUT DI/DT=1A/US
(11275 4480) 0;
DISPLAY LEFT (11275 4480);
DISPLAY 0.617021 (11275 4480);
PAINT PURPLE (11275 4480);
FORCENOTE
AC TOLERANCE & RIPPLE=+/-3.0%
(11275 4580) 0;
DISPLAY LEFT (11275 4580);
DISPLAY 0.617021 (11275 4580);
PAINT PURPLE (11275 4580);
FORCENOTE
TP FAB1 CHANGE SMALL SIZE CHOCK FOR PLACEMENT 0203
(10075 4175) 0;
DISPLAY LEFT (10075 4175);
DISPLAY 0.638298 (10075 4175);
PAINT RED (10075 4175);
FORCENOTE
TP FAB1 CHANGE CAP PN TO AVOID ME INTERFERENCE 0203
(11050 3450) 0;
DISPLAY LEFT (11050 3450);
DISPLAY 0.638298 (11050 3450);
PAINT RED (11050 3450);
FORCENOTE
TP FAB3 CHANGE RES  0823
(6775 1650) 0;
DISPLAY LEFT (6775 1650);
DISPLAY 0.638298 (6775 1650);
PAINT RED (6775 1650);
FORCENOTE
23.5A OC
(6505 1555) 0;
DISPLAY LEFT (6505 1555);
PAINT PURPLE (6505 1555);
FORCENOTE
DC TOLERANCE=+-1.5%
(11275 4680) 0;
DISPLAY LEFT (11275 4680);
DISPLAY 0.617021 (11275 4680);
PAINT PURPLE (11275 4680);
FORCENOTE
TP FAB1 CHANGE ONE 47UF CPA TO TWO 22UF CAPS 0107
(7200 4650) 0;
DISPLAY LEFT (7200 4650);
DISPLAY 1.021277 (7200 4650);
PAINT RED (7200 4650);
FORCENOTE
POINT ONLY TOP TO L2
(10125 1875) 0;
DISPLAY LEFT (10125 1875);
DISPLAY 1.042553 (10125 1875);
PAINT PURPLE (10125 1875);
FORCENOTE
IMAX= 25.59A
(11275 4380) 0;
DISPLAY LEFT (11275 4380);
DISPLAY 0.617021 (11275 4380);
PAINT PURPLE (11275 4380);
QUIT
